FILE_TYPE = MACRO_DRAWING;
SET COLOR_WIRE YELLOW;
SET COLOR_PROP ORANGE;
SET COLOR_DOT WHITE;
SET COLOR_ARC YELLOW;
SET COLOR_BODY GREEN;
SET COLOR_NOTE PURPLE;
SET PROP_DISPLAY VALUE;
SET PAGE_NUMBER P106;
FORCEADD OFFPAGE..6
(-8150 3525);
FORCEPROP 2 LAST $XR0 46 
J 0
(-8429 3525);
DISPLAY 0.638298 (-8429 3525);
PAINT MONO (-8429 3525);
FORCEPROP 2 LAST PATH I10
J 0
(-8375 3575);
DISPLAY 1.021277 (-8375 3575);
DISPLAY INVISIBLE (-8375 3575);
FORCEPROP 1 LAST COMMENT_BODY TRUE
J 0
(-8050 3450);
DISPLAY 0.872340 (-8050 3450);
PAINT GREEN (-8050 3450);
DISPLAY INVISIBLE (-8050 3450);
FORCEPROP 1 LAST OFFPAGE TRUE
J 0
(-7825 3400);
DISPLAY 0.872340 (-7825 3400);
PAINT GREEN (-7825 3400);
DISPLAY INVISIBLE (-7825 3400);
FORCEPROP 2 LAST CDS_LIB mstr_standard
J 0
(-8150 3525);
DISPLAY 0.723404 (-8150 3525);
PAINT MONO (-8150 3525);
DISPLAY INVISIBLE (-8150 3525);
FORCEADD TAP..1
(-5850 4125);
FORCEPROP 3 LASTPIN (-5900 4125) SIG_NAME M_J_CPU1_SA_DQ<7>
J 0
(-5890 4135);
DISPLAY 0.659574 (-5890 4135);
PAINT MONO (-5890 4135);
DISPLAY INVISIBLE (-5890 4135);
FORCEPROP 1 LASTPIN (-5900 4125) BN 7
J 0
(-5912 4133);
DISPLAY 0.489362 (-5912 4133);
PAINT GREEN (-5912 4133);
FORCEPROP 2 LAST CDS_LIB mstr_standard
J 0
(-5850 4125);
DISPLAY 0.723404 (-5850 4125);
PAINT MONO (-5850 4125);
DISPLAY INVISIBLE (-5850 4125);
FORCEPROP 1 LAST BODY_TYPE PLUMBING
J 0
(-5850 4175);
DISPLAY 0.872340 (-5850 4175);
PAINT GREEN (-5850 4175);
DISPLAY INVISIBLE (-5850 4175);
FORCEPROP 1 LAST HDL_TAP TRUE
J 0
(-5525 4000);
DISPLAY 0.872340 (-5525 4000);
DISPLAY INVISIBLE (-5525 4000);
FORCEPROP 1 LAST PATH I100
J 0
(-5852 4125);
DISPLAY 0.872340 (-5852 4125);
PAINT GREEN (-5852 4125);
DISPLAY INVISIBLE (-5852 4125);
FORCEADD TAP..1
(-5850 4175);
FORCEPROP 3 LASTPIN (-5900 4175) SIG_NAME M_J_CPU1_SA_DQ<8>
J 0
(-5890 4185);
DISPLAY 0.659574 (-5890 4185);
PAINT MONO (-5890 4185);
DISPLAY INVISIBLE (-5890 4185);
FORCEPROP 1 LASTPIN (-5900 4175) BN 8
J 0
(-5912 4183);
DISPLAY 0.489362 (-5912 4183);
PAINT GREEN (-5912 4183);
FORCEPROP 2 LAST CDS_LIB mstr_standard
J 0
(-5850 4175);
DISPLAY 0.723404 (-5850 4175);
PAINT MONO (-5850 4175);
DISPLAY INVISIBLE (-5850 4175);
FORCEPROP 1 LAST BODY_TYPE PLUMBING
J 0
(-5850 4225);
DISPLAY 0.872340 (-5850 4225);
PAINT GREEN (-5850 4225);
DISPLAY INVISIBLE (-5850 4225);
FORCEPROP 1 LAST HDL_TAP TRUE
J 0
(-5525 4050);
DISPLAY 0.872340 (-5525 4050);
DISPLAY INVISIBLE (-5525 4050);
FORCEPROP 1 LAST PATH I101
J 0
(-5852 4175);
DISPLAY 0.872340 (-5852 4175);
PAINT GREEN (-5852 4175);
DISPLAY INVISIBLE (-5852 4175);
FORCEADD TAP..1
(-5850 4225);
FORCEPROP 3 LASTPIN (-5900 4225) SIG_NAME M_J_CPU1_SA_DQ<9>
J 0
(-5890 4235);
DISPLAY 0.659574 (-5890 4235);
PAINT MONO (-5890 4235);
DISPLAY INVISIBLE (-5890 4235);
FORCEPROP 1 LASTPIN (-5900 4225) BN 9
J 0
(-5912 4233);
DISPLAY 0.489362 (-5912 4233);
PAINT GREEN (-5912 4233);
FORCEPROP 2 LAST CDS_LIB mstr_standard
J 0
(-5850 4225);
DISPLAY 0.723404 (-5850 4225);
PAINT MONO (-5850 4225);
DISPLAY INVISIBLE (-5850 4225);
FORCEPROP 1 LAST BODY_TYPE PLUMBING
J 0
(-5850 4275);
DISPLAY 0.872340 (-5850 4275);
PAINT GREEN (-5850 4275);
DISPLAY INVISIBLE (-5850 4275);
FORCEPROP 1 LAST HDL_TAP TRUE
J 0
(-5525 4100);
DISPLAY 0.872340 (-5525 4100);
DISPLAY INVISIBLE (-5525 4100);
FORCEPROP 1 LAST PATH I102
J 0
(-5852 4225);
DISPLAY 0.872340 (-5852 4225);
PAINT GREEN (-5852 4225);
DISPLAY INVISIBLE (-5852 4225);
FORCEADD TAP..1
(-5850 4275);
FORCEPROP 3 LASTPIN (-5900 4275) SIG_NAME M_J_CPU1_SA_DQ<10>
J 0
(-5890 4285);
DISPLAY 0.659574 (-5890 4285);
PAINT MONO (-5890 4285);
DISPLAY INVISIBLE (-5890 4285);
FORCEPROP 1 LASTPIN (-5900 4275) BN 10
J 0
(-5912 4283);
DISPLAY 0.489362 (-5912 4283);
PAINT GREEN (-5912 4283);
FORCEPROP 2 LAST CDS_LIB mstr_standard
J 0
(-5850 4275);
DISPLAY 0.723404 (-5850 4275);
PAINT MONO (-5850 4275);
DISPLAY INVISIBLE (-5850 4275);
FORCEPROP 1 LAST BODY_TYPE PLUMBING
J 0
(-5850 4325);
DISPLAY 0.872340 (-5850 4325);
PAINT GREEN (-5850 4325);
DISPLAY INVISIBLE (-5850 4325);
FORCEPROP 1 LAST HDL_TAP TRUE
J 0
(-5525 4150);
DISPLAY 0.872340 (-5525 4150);
DISPLAY INVISIBLE (-5525 4150);
FORCEPROP 1 LAST PATH I103
J 0
(-5852 4275);
DISPLAY 0.872340 (-5852 4275);
PAINT GREEN (-5852 4275);
DISPLAY INVISIBLE (-5852 4275);
FORCEADD TAP..1
(-5850 4375);
FORCEPROP 3 LASTPIN (-5900 4375) SIG_NAME M_J_CPU1_SA_DQ<12>
J 0
(-5890 4385);
DISPLAY 0.659574 (-5890 4385);
PAINT MONO (-5890 4385);
DISPLAY INVISIBLE (-5890 4385);
FORCEPROP 1 LASTPIN (-5900 4375) BN 12
J 0
(-5912 4383);
DISPLAY 0.489362 (-5912 4383);
PAINT GREEN (-5912 4383);
FORCEPROP 2 LAST CDS_LIB mstr_standard
J 0
(-5850 4375);
DISPLAY 0.723404 (-5850 4375);
PAINT MONO (-5850 4375);
DISPLAY INVISIBLE (-5850 4375);
FORCEPROP 1 LAST BODY_TYPE PLUMBING
J 0
(-5850 4425);
DISPLAY 0.872340 (-5850 4425);
PAINT GREEN (-5850 4425);
DISPLAY INVISIBLE (-5850 4425);
FORCEPROP 1 LAST HDL_TAP TRUE
J 0
(-5525 4250);
DISPLAY 0.872340 (-5525 4250);
DISPLAY INVISIBLE (-5525 4250);
FORCEPROP 1 LAST PATH I104
J 0
(-5852 4375);
DISPLAY 0.872340 (-5852 4375);
PAINT GREEN (-5852 4375);
DISPLAY INVISIBLE (-5852 4375);
FORCEADD TAP..1
(-5850 4325);
FORCEPROP 3 LASTPIN (-5900 4325) SIG_NAME M_J_CPU1_SA_DQ<11>
J 0
(-5890 4335);
DISPLAY 0.659574 (-5890 4335);
PAINT MONO (-5890 4335);
DISPLAY INVISIBLE (-5890 4335);
FORCEPROP 1 LASTPIN (-5900 4325) BN 11
J 0
(-5912 4333);
DISPLAY 0.489362 (-5912 4333);
PAINT GREEN (-5912 4333);
FORCEPROP 2 LAST CDS_LIB mstr_standard
J 0
(-5850 4325);
DISPLAY 0.723404 (-5850 4325);
PAINT MONO (-5850 4325);
DISPLAY INVISIBLE (-5850 4325);
FORCEPROP 1 LAST BODY_TYPE PLUMBING
J 0
(-5850 4375);
DISPLAY 0.872340 (-5850 4375);
PAINT GREEN (-5850 4375);
DISPLAY INVISIBLE (-5850 4375);
FORCEPROP 1 LAST HDL_TAP TRUE
J 0
(-5525 4200);
DISPLAY 0.872340 (-5525 4200);
DISPLAY INVISIBLE (-5525 4200);
FORCEPROP 1 LAST PATH I105
J 0
(-5852 4325);
DISPLAY 0.872340 (-5852 4325);
PAINT GREEN (-5852 4325);
DISPLAY INVISIBLE (-5852 4325);
FORCEADD TAP..1
(-5850 4425);
FORCEPROP 3 LASTPIN (-5900 4425) SIG_NAME M_J_CPU1_SA_DQ<13>
J 0
(-5890 4435);
DISPLAY 0.659574 (-5890 4435);
PAINT MONO (-5890 4435);
DISPLAY INVISIBLE (-5890 4435);
FORCEPROP 1 LASTPIN (-5900 4425) BN 13
J 0
(-5912 4433);
DISPLAY 0.489362 (-5912 4433);
PAINT GREEN (-5912 4433);
FORCEPROP 2 LAST CDS_LIB mstr_standard
J 0
(-5850 4425);
DISPLAY 0.723404 (-5850 4425);
PAINT MONO (-5850 4425);
DISPLAY INVISIBLE (-5850 4425);
FORCEPROP 1 LAST BODY_TYPE PLUMBING
J 0
(-5850 4475);
DISPLAY 0.872340 (-5850 4475);
PAINT GREEN (-5850 4475);
DISPLAY INVISIBLE (-5850 4475);
FORCEPROP 1 LAST HDL_TAP TRUE
J 0
(-5525 4300);
DISPLAY 0.872340 (-5525 4300);
DISPLAY INVISIBLE (-5525 4300);
FORCEPROP 1 LAST PATH I106
J 0
(-5852 4425);
DISPLAY 0.872340 (-5852 4425);
PAINT GREEN (-5852 4425);
DISPLAY INVISIBLE (-5852 4425);
FORCEADD TAP..1
(-5850 4475);
FORCEPROP 3 LASTPIN (-5900 4475) SIG_NAME M_J_CPU1_SA_DQ<14>
J 0
(-5890 4485);
DISPLAY 0.659574 (-5890 4485);
PAINT MONO (-5890 4485);
DISPLAY INVISIBLE (-5890 4485);
FORCEPROP 1 LASTPIN (-5900 4475) BN 14
J 0
(-5912 4483);
DISPLAY 0.489362 (-5912 4483);
PAINT GREEN (-5912 4483);
FORCEPROP 2 LAST CDS_LIB mstr_standard
J 0
(-5850 4475);
DISPLAY 0.723404 (-5850 4475);
PAINT MONO (-5850 4475);
DISPLAY INVISIBLE (-5850 4475);
FORCEPROP 1 LAST BODY_TYPE PLUMBING
J 0
(-5850 4525);
DISPLAY 0.872340 (-5850 4525);
PAINT GREEN (-5850 4525);
DISPLAY INVISIBLE (-5850 4525);
FORCEPROP 1 LAST HDL_TAP TRUE
J 0
(-5525 4350);
DISPLAY 0.872340 (-5525 4350);
DISPLAY INVISIBLE (-5525 4350);
FORCEPROP 1 LAST PATH I107
J 0
(-5852 4475);
DISPLAY 0.872340 (-5852 4475);
PAINT GREEN (-5852 4475);
DISPLAY INVISIBLE (-5852 4475);
FORCEADD TAP..1
(-5850 4525);
FORCEPROP 3 LASTPIN (-5900 4525) SIG_NAME M_J_CPU1_SA_DQ<15>
J 0
(-5890 4535);
DISPLAY 0.659574 (-5890 4535);
PAINT MONO (-5890 4535);
DISPLAY INVISIBLE (-5890 4535);
FORCEPROP 1 LASTPIN (-5900 4525) BN 15
J 0
(-5912 4533);
DISPLAY 0.489362 (-5912 4533);
PAINT GREEN (-5912 4533);
FORCEPROP 2 LAST CDS_LIB mstr_standard
J 0
(-5850 4525);
DISPLAY 0.723404 (-5850 4525);
PAINT MONO (-5850 4525);
DISPLAY INVISIBLE (-5850 4525);
FORCEPROP 1 LAST BODY_TYPE PLUMBING
J 0
(-5850 4575);
DISPLAY 0.872340 (-5850 4575);
PAINT GREEN (-5850 4575);
DISPLAY INVISIBLE (-5850 4575);
FORCEPROP 1 LAST HDL_TAP TRUE
J 0
(-5525 4400);
DISPLAY 0.872340 (-5525 4400);
DISPLAY INVISIBLE (-5525 4400);
FORCEPROP 1 LAST PATH I108
J 0
(-5852 4525);
DISPLAY 0.872340 (-5852 4525);
PAINT GREEN (-5852 4525);
DISPLAY INVISIBLE (-5852 4525);
FORCEADD TAP..1
(-5850 4575);
FORCEPROP 3 LASTPIN (-5900 4575) SIG_NAME M_J_CPU1_SA_DQ<16>
J 0
(-5890 4585);
DISPLAY 0.659574 (-5890 4585);
PAINT MONO (-5890 4585);
DISPLAY INVISIBLE (-5890 4585);
FORCEPROP 1 LASTPIN (-5900 4575) BN 16
J 0
(-5912 4583);
DISPLAY 0.489362 (-5912 4583);
PAINT GREEN (-5912 4583);
FORCEPROP 2 LAST CDS_LIB mstr_standard
J 0
(-5850 4575);
DISPLAY 0.723404 (-5850 4575);
PAINT MONO (-5850 4575);
DISPLAY INVISIBLE (-5850 4575);
FORCEPROP 1 LAST BODY_TYPE PLUMBING
J 0
(-5850 4625);
DISPLAY 0.872340 (-5850 4625);
PAINT GREEN (-5850 4625);
DISPLAY INVISIBLE (-5850 4625);
FORCEPROP 1 LAST HDL_TAP TRUE
J 0
(-5525 4450);
DISPLAY 0.872340 (-5525 4450);
DISPLAY INVISIBLE (-5525 4450);
FORCEPROP 1 LAST PATH I109
J 0
(-5852 4575);
DISPLAY 0.872340 (-5852 4575);
PAINT GREEN (-5852 4575);
DISPLAY INVISIBLE (-5852 4575);
FORCEADD OFFPAGE..6
(-8150 3975);
FORCEPROP 2 LAST $XR0 46 
J 0
(-8429 3975);
DISPLAY 0.638298 (-8429 3975);
PAINT MONO (-8429 3975);
FORCEPROP 2 LAST PATH I11
J 0
(-8375 4025);
DISPLAY 1.021277 (-8375 4025);
DISPLAY INVISIBLE (-8375 4025);
FORCEPROP 1 LAST COMMENT_BODY TRUE
J 0
(-8050 3900);
DISPLAY 0.872340 (-8050 3900);
PAINT GREEN (-8050 3900);
DISPLAY INVISIBLE (-8050 3900);
FORCEPROP 1 LAST OFFPAGE TRUE
J 0
(-7825 3850);
DISPLAY 0.872340 (-7825 3850);
PAINT GREEN (-7825 3850);
DISPLAY INVISIBLE (-7825 3850);
FORCEPROP 2 LAST CDS_LIB mstr_standard
J 0
(-8150 3975);
DISPLAY 0.723404 (-8150 3975);
PAINT MONO (-8150 3975);
DISPLAY INVISIBLE (-8150 3975);
FORCEADD TAP..1
(-5850 4625);
FORCEPROP 3 LASTPIN (-5900 4625) SIG_NAME M_J_CPU1_SA_DQ<17>
J 0
(-5890 4635);
DISPLAY 0.659574 (-5890 4635);
PAINT MONO (-5890 4635);
DISPLAY INVISIBLE (-5890 4635);
FORCEPROP 1 LASTPIN (-5900 4625) BN 17
J 0
(-5912 4633);
DISPLAY 0.489362 (-5912 4633);
PAINT GREEN (-5912 4633);
FORCEPROP 2 LAST CDS_LIB mstr_standard
J 0
(-5850 4625);
DISPLAY 0.723404 (-5850 4625);
PAINT MONO (-5850 4625);
DISPLAY INVISIBLE (-5850 4625);
FORCEPROP 1 LAST BODY_TYPE PLUMBING
J 0
(-5850 4675);
DISPLAY 0.872340 (-5850 4675);
PAINT GREEN (-5850 4675);
DISPLAY INVISIBLE (-5850 4675);
FORCEPROP 1 LAST HDL_TAP TRUE
J 0
(-5525 4500);
DISPLAY 0.872340 (-5525 4500);
DISPLAY INVISIBLE (-5525 4500);
FORCEPROP 1 LAST PATH I110
J 0
(-5852 4625);
DISPLAY 0.872340 (-5852 4625);
PAINT GREEN (-5852 4625);
DISPLAY INVISIBLE (-5852 4625);
FORCEADD TAP..1
(-5850 4675);
FORCEPROP 3 LASTPIN (-5900 4675) SIG_NAME M_J_CPU1_SA_DQ<18>
J 0
(-5890 4685);
DISPLAY 0.659574 (-5890 4685);
PAINT MONO (-5890 4685);
DISPLAY INVISIBLE (-5890 4685);
FORCEPROP 1 LASTPIN (-5900 4675) BN 18
J 0
(-5912 4683);
DISPLAY 0.489362 (-5912 4683);
PAINT GREEN (-5912 4683);
FORCEPROP 2 LAST CDS_LIB mstr_standard
J 0
(-5850 4675);
DISPLAY 0.723404 (-5850 4675);
PAINT MONO (-5850 4675);
DISPLAY INVISIBLE (-5850 4675);
FORCEPROP 1 LAST BODY_TYPE PLUMBING
J 0
(-5850 4725);
DISPLAY 0.872340 (-5850 4725);
PAINT GREEN (-5850 4725);
DISPLAY INVISIBLE (-5850 4725);
FORCEPROP 1 LAST HDL_TAP TRUE
J 0
(-5525 4550);
DISPLAY 0.872340 (-5525 4550);
DISPLAY INVISIBLE (-5525 4550);
FORCEPROP 1 LAST PATH I111
J 0
(-5852 4675);
DISPLAY 0.872340 (-5852 4675);
PAINT GREEN (-5852 4675);
DISPLAY INVISIBLE (-5852 4675);
FORCEADD TAP..1
(-5850 4725);
FORCEPROP 3 LASTPIN (-5900 4725) SIG_NAME M_J_CPU1_SA_DQ<19>
J 0
(-5890 4735);
DISPLAY 0.659574 (-5890 4735);
PAINT MONO (-5890 4735);
DISPLAY INVISIBLE (-5890 4735);
FORCEPROP 1 LASTPIN (-5900 4725) BN 19
J 0
(-5912 4733);
DISPLAY 0.489362 (-5912 4733);
PAINT GREEN (-5912 4733);
FORCEPROP 2 LAST CDS_LIB mstr_standard
J 0
(-5850 4725);
DISPLAY 0.723404 (-5850 4725);
PAINT MONO (-5850 4725);
DISPLAY INVISIBLE (-5850 4725);
FORCEPROP 1 LAST BODY_TYPE PLUMBING
J 0
(-5850 4775);
DISPLAY 0.872340 (-5850 4775);
PAINT GREEN (-5850 4775);
DISPLAY INVISIBLE (-5850 4775);
FORCEPROP 1 LAST HDL_TAP TRUE
J 0
(-5525 4600);
DISPLAY 0.872340 (-5525 4600);
DISPLAY INVISIBLE (-5525 4600);
FORCEPROP 1 LAST PATH I112
J 0
(-5852 4725);
DISPLAY 0.872340 (-5852 4725);
PAINT GREEN (-5852 4725);
DISPLAY INVISIBLE (-5852 4725);
FORCEADD TAP..1
(-5850 4775);
FORCEPROP 3 LASTPIN (-5900 4775) SIG_NAME M_J_CPU1_SA_DQ<20>
J 0
(-5890 4785);
DISPLAY 0.659574 (-5890 4785);
PAINT MONO (-5890 4785);
DISPLAY INVISIBLE (-5890 4785);
FORCEPROP 1 LASTPIN (-5900 4775) BN 20
J 0
(-5912 4783);
DISPLAY 0.489362 (-5912 4783);
PAINT GREEN (-5912 4783);
FORCEPROP 2 LAST CDS_LIB mstr_standard
J 0
(-5850 4775);
DISPLAY 0.723404 (-5850 4775);
PAINT MONO (-5850 4775);
DISPLAY INVISIBLE (-5850 4775);
FORCEPROP 1 LAST BODY_TYPE PLUMBING
J 0
(-5850 4825);
DISPLAY 0.872340 (-5850 4825);
PAINT GREEN (-5850 4825);
DISPLAY INVISIBLE (-5850 4825);
FORCEPROP 1 LAST HDL_TAP TRUE
J 0
(-5525 4650);
DISPLAY 0.872340 (-5525 4650);
DISPLAY INVISIBLE (-5525 4650);
FORCEPROP 1 LAST PATH I113
J 0
(-5852 4775);
DISPLAY 0.872340 (-5852 4775);
PAINT GREEN (-5852 4775);
DISPLAY INVISIBLE (-5852 4775);
FORCEADD TAP..1
(-5850 4825);
FORCEPROP 3 LASTPIN (-5900 4825) SIG_NAME M_J_CPU1_SA_DQ<21>
J 0
(-5890 4835);
DISPLAY 0.659574 (-5890 4835);
PAINT MONO (-5890 4835);
DISPLAY INVISIBLE (-5890 4835);
FORCEPROP 1 LASTPIN (-5900 4825) BN 21
J 0
(-5912 4833);
DISPLAY 0.489362 (-5912 4833);
PAINT GREEN (-5912 4833);
FORCEPROP 2 LAST CDS_LIB mstr_standard
J 0
(-5850 4825);
DISPLAY 0.723404 (-5850 4825);
PAINT MONO (-5850 4825);
DISPLAY INVISIBLE (-5850 4825);
FORCEPROP 1 LAST BODY_TYPE PLUMBING
J 0
(-5850 4875);
DISPLAY 0.872340 (-5850 4875);
PAINT GREEN (-5850 4875);
DISPLAY INVISIBLE (-5850 4875);
FORCEPROP 1 LAST HDL_TAP TRUE
J 0
(-5525 4700);
DISPLAY 0.872340 (-5525 4700);
DISPLAY INVISIBLE (-5525 4700);
FORCEPROP 1 LAST PATH I114
J 0
(-5852 4825);
DISPLAY 0.872340 (-5852 4825);
PAINT GREEN (-5852 4825);
DISPLAY INVISIBLE (-5852 4825);
FORCEADD TAP..1
(-5850 4875);
FORCEPROP 3 LASTPIN (-5900 4875) SIG_NAME M_J_CPU1_SA_DQ<22>
J 0
(-5890 4885);
DISPLAY 0.659574 (-5890 4885);
PAINT MONO (-5890 4885);
DISPLAY INVISIBLE (-5890 4885);
FORCEPROP 1 LASTPIN (-5900 4875) BN 22
J 0
(-5912 4883);
DISPLAY 0.489362 (-5912 4883);
PAINT GREEN (-5912 4883);
FORCEPROP 2 LAST CDS_LIB mstr_standard
J 0
(-5850 4875);
DISPLAY 0.723404 (-5850 4875);
PAINT MONO (-5850 4875);
DISPLAY INVISIBLE (-5850 4875);
FORCEPROP 1 LAST BODY_TYPE PLUMBING
J 0
(-5850 4925);
DISPLAY 0.872340 (-5850 4925);
PAINT GREEN (-5850 4925);
DISPLAY INVISIBLE (-5850 4925);
FORCEPROP 1 LAST HDL_TAP TRUE
J 0
(-5525 4750);
DISPLAY 0.872340 (-5525 4750);
DISPLAY INVISIBLE (-5525 4750);
FORCEPROP 1 LAST PATH I115
J 0
(-5852 4875);
DISPLAY 0.872340 (-5852 4875);
PAINT GREEN (-5852 4875);
DISPLAY INVISIBLE (-5852 4875);
FORCEADD TAP..1
(-5850 4925);
FORCEPROP 3 LASTPIN (-5900 4925) SIG_NAME M_J_CPU1_SA_DQ<23>
J 0
(-5890 4935);
DISPLAY 0.659574 (-5890 4935);
PAINT MONO (-5890 4935);
DISPLAY INVISIBLE (-5890 4935);
FORCEPROP 1 LASTPIN (-5900 4925) BN 23
J 0
(-5912 4933);
DISPLAY 0.489362 (-5912 4933);
PAINT GREEN (-5912 4933);
FORCEPROP 2 LAST CDS_LIB mstr_standard
J 0
(-5850 4925);
DISPLAY 0.723404 (-5850 4925);
PAINT MONO (-5850 4925);
DISPLAY INVISIBLE (-5850 4925);
FORCEPROP 1 LAST BODY_TYPE PLUMBING
J 0
(-5850 4975);
DISPLAY 0.872340 (-5850 4975);
PAINT GREEN (-5850 4975);
DISPLAY INVISIBLE (-5850 4975);
FORCEPROP 1 LAST HDL_TAP TRUE
J 0
(-5525 4800);
DISPLAY 0.872340 (-5525 4800);
DISPLAY INVISIBLE (-5525 4800);
FORCEPROP 1 LAST PATH I116
J 0
(-5852 4925);
DISPLAY 0.872340 (-5852 4925);
PAINT GREEN (-5852 4925);
DISPLAY INVISIBLE (-5852 4925);
FORCEADD TAP..1
(-5850 4975);
FORCEPROP 3 LASTPIN (-5900 4975) SIG_NAME M_J_CPU1_SA_DQ<24>
J 0
(-5890 4985);
DISPLAY 0.659574 (-5890 4985);
PAINT MONO (-5890 4985);
DISPLAY INVISIBLE (-5890 4985);
FORCEPROP 1 LASTPIN (-5900 4975) BN 24
J 0
(-5912 4983);
DISPLAY 0.489362 (-5912 4983);
PAINT GREEN (-5912 4983);
FORCEPROP 2 LAST CDS_LIB mstr_standard
J 0
(-5850 4975);
DISPLAY 0.723404 (-5850 4975);
PAINT MONO (-5850 4975);
DISPLAY INVISIBLE (-5850 4975);
FORCEPROP 1 LAST BODY_TYPE PLUMBING
J 0
(-5850 5025);
DISPLAY 0.872340 (-5850 5025);
PAINT GREEN (-5850 5025);
DISPLAY INVISIBLE (-5850 5025);
FORCEPROP 1 LAST HDL_TAP TRUE
J 0
(-5525 4850);
DISPLAY 0.872340 (-5525 4850);
DISPLAY INVISIBLE (-5525 4850);
FORCEPROP 1 LAST PATH I117
J 0
(-5852 4975);
DISPLAY 0.872340 (-5852 4975);
PAINT GREEN (-5852 4975);
DISPLAY INVISIBLE (-5852 4975);
FORCEADD TAP..1
(-5850 5025);
FORCEPROP 3 LASTPIN (-5900 5025) SIG_NAME M_J_CPU1_SA_DQ<25>
J 0
(-5890 5035);
DISPLAY 0.659574 (-5890 5035);
PAINT MONO (-5890 5035);
DISPLAY INVISIBLE (-5890 5035);
FORCEPROP 1 LASTPIN (-5900 5025) BN 25
J 0
(-5912 5033);
DISPLAY 0.489362 (-5912 5033);
PAINT GREEN (-5912 5033);
FORCEPROP 2 LAST CDS_LIB mstr_standard
J 0
(-5850 5025);
DISPLAY 0.723404 (-5850 5025);
PAINT MONO (-5850 5025);
DISPLAY INVISIBLE (-5850 5025);
FORCEPROP 1 LAST BODY_TYPE PLUMBING
J 0
(-5850 5075);
DISPLAY 0.872340 (-5850 5075);
PAINT GREEN (-5850 5075);
DISPLAY INVISIBLE (-5850 5075);
FORCEPROP 1 LAST HDL_TAP TRUE
J 0
(-5525 4900);
DISPLAY 0.872340 (-5525 4900);
DISPLAY INVISIBLE (-5525 4900);
FORCEPROP 1 LAST PATH I118
J 0
(-5852 5025);
DISPLAY 0.872340 (-5852 5025);
PAINT GREEN (-5852 5025);
DISPLAY INVISIBLE (-5852 5025);
FORCEADD TAP..1
(-5850 5075);
FORCEPROP 3 LASTPIN (-5900 5075) SIG_NAME M_J_CPU1_SA_DQ<26>
J 0
(-5890 5085);
DISPLAY 0.659574 (-5890 5085);
PAINT MONO (-5890 5085);
DISPLAY INVISIBLE (-5890 5085);
FORCEPROP 1 LASTPIN (-5900 5075) BN 26
J 0
(-5912 5083);
DISPLAY 0.489362 (-5912 5083);
PAINT GREEN (-5912 5083);
FORCEPROP 2 LAST CDS_LIB mstr_standard
J 0
(-5850 5075);
DISPLAY 0.723404 (-5850 5075);
PAINT MONO (-5850 5075);
DISPLAY INVISIBLE (-5850 5075);
FORCEPROP 1 LAST BODY_TYPE PLUMBING
J 0
(-5850 5125);
DISPLAY 0.872340 (-5850 5125);
PAINT GREEN (-5850 5125);
DISPLAY INVISIBLE (-5850 5125);
FORCEPROP 1 LAST HDL_TAP TRUE
J 0
(-5525 4950);
DISPLAY 0.872340 (-5525 4950);
DISPLAY INVISIBLE (-5525 4950);
FORCEPROP 1 LAST PATH I119
J 0
(-5852 5075);
DISPLAY 0.872340 (-5852 5075);
PAINT GREEN (-5852 5075);
DISPLAY INVISIBLE (-5852 5075);
FORCEADD OFFPAGE..1
(-8150 4025);
FORCEPROP 2 LAST $XR0 46 
J 0
(-8401 4025);
DISPLAY 0.638298 (-8401 4025);
PAINT MONO (-8401 4025);
FORCEPROP 2 LAST PATH I12
J 0
(-8400 4075);
DISPLAY 1.021277 (-8400 4075);
DISPLAY INVISIBLE (-8400 4075);
FORCEPROP 1 LAST COMMENT_BODY TRUE
J 0
(-8025 3925);
DISPLAY 0.872340 (-8025 3925);
PAINT GREEN (-8025 3925);
DISPLAY INVISIBLE (-8025 3925);
FORCEPROP 1 LAST OFFPAGE TRUE
J 0
(-7825 3900);
DISPLAY 0.872340 (-7825 3900);
PAINT GREEN (-7825 3900);
DISPLAY INVISIBLE (-7825 3900);
FORCEPROP 2 LAST CDS_LIB mstr_standard
J 0
(-8150 4025);
DISPLAY 0.808511 (-8150 4025);
DISPLAY INVISIBLE (-8150 4025);
FORCEADD TAP..1
(-5850 5125);
FORCEPROP 3 LASTPIN (-5900 5125) SIG_NAME M_J_CPU1_SA_DQ<27>
J 0
(-5890 5135);
DISPLAY 0.659574 (-5890 5135);
PAINT MONO (-5890 5135);
DISPLAY INVISIBLE (-5890 5135);
FORCEPROP 1 LASTPIN (-5900 5125) BN 27
J 0
(-5912 5133);
DISPLAY 0.489362 (-5912 5133);
PAINT GREEN (-5912 5133);
FORCEPROP 2 LAST CDS_LIB mstr_standard
J 0
(-5850 5125);
DISPLAY 0.723404 (-5850 5125);
PAINT MONO (-5850 5125);
DISPLAY INVISIBLE (-5850 5125);
FORCEPROP 1 LAST BODY_TYPE PLUMBING
J 0
(-5850 5175);
DISPLAY 0.872340 (-5850 5175);
PAINT GREEN (-5850 5175);
DISPLAY INVISIBLE (-5850 5175);
FORCEPROP 1 LAST HDL_TAP TRUE
J 0
(-5525 5000);
DISPLAY 0.872340 (-5525 5000);
DISPLAY INVISIBLE (-5525 5000);
FORCEPROP 1 LAST PATH I120
J 0
(-5852 5125);
DISPLAY 0.872340 (-5852 5125);
PAINT GREEN (-5852 5125);
DISPLAY INVISIBLE (-5852 5125);
FORCEADD TAP..1
(-5850 5175);
FORCEPROP 3 LASTPIN (-5900 5175) SIG_NAME M_J_CPU1_SA_DQ<28>
J 0
(-5890 5185);
DISPLAY 0.659574 (-5890 5185);
PAINT MONO (-5890 5185);
DISPLAY INVISIBLE (-5890 5185);
FORCEPROP 1 LASTPIN (-5900 5175) BN 28
J 0
(-5912 5183);
DISPLAY 0.489362 (-5912 5183);
PAINT GREEN (-5912 5183);
FORCEPROP 2 LAST CDS_LIB mstr_standard
J 0
(-5850 5175);
DISPLAY 0.723404 (-5850 5175);
PAINT MONO (-5850 5175);
DISPLAY INVISIBLE (-5850 5175);
FORCEPROP 1 LAST BODY_TYPE PLUMBING
J 0
(-5850 5225);
DISPLAY 0.872340 (-5850 5225);
PAINT GREEN (-5850 5225);
DISPLAY INVISIBLE (-5850 5225);
FORCEPROP 1 LAST HDL_TAP TRUE
J 0
(-5525 5050);
DISPLAY 0.872340 (-5525 5050);
DISPLAY INVISIBLE (-5525 5050);
FORCEPROP 1 LAST PATH I121
J 0
(-5852 5175);
DISPLAY 0.872340 (-5852 5175);
PAINT GREEN (-5852 5175);
DISPLAY INVISIBLE (-5852 5175);
FORCEADD TAP..1
(-5850 5275);
FORCEPROP 3 LASTPIN (-5900 5275) SIG_NAME M_J_CPU1_SA_DQ<30>
J 0
(-5890 5285);
DISPLAY 0.659574 (-5890 5285);
PAINT MONO (-5890 5285);
DISPLAY INVISIBLE (-5890 5285);
FORCEPROP 1 LASTPIN (-5900 5275) BN 30
J 0
(-5912 5283);
DISPLAY 0.489362 (-5912 5283);
PAINT GREEN (-5912 5283);
FORCEPROP 2 LAST CDS_LIB mstr_standard
J 0
(-5850 5275);
DISPLAY 0.723404 (-5850 5275);
PAINT MONO (-5850 5275);
DISPLAY INVISIBLE (-5850 5275);
FORCEPROP 1 LAST BODY_TYPE PLUMBING
J 0
(-5850 5325);
DISPLAY 0.872340 (-5850 5325);
PAINT GREEN (-5850 5325);
DISPLAY INVISIBLE (-5850 5325);
FORCEPROP 1 LAST HDL_TAP TRUE
J 0
(-5525 5150);
DISPLAY 0.872340 (-5525 5150);
DISPLAY INVISIBLE (-5525 5150);
FORCEPROP 1 LAST PATH I122
J 0
(-5852 5275);
DISPLAY 0.872340 (-5852 5275);
PAINT GREEN (-5852 5275);
DISPLAY INVISIBLE (-5852 5275);
FORCEADD TAP..1
(-5850 5225);
FORCEPROP 3 LASTPIN (-5900 5225) SIG_NAME M_J_CPU1_SA_DQ<29>
J 0
(-5890 5235);
DISPLAY 0.659574 (-5890 5235);
PAINT MONO (-5890 5235);
DISPLAY INVISIBLE (-5890 5235);
FORCEPROP 1 LASTPIN (-5900 5225) BN 29
J 0
(-5912 5233);
DISPLAY 0.489362 (-5912 5233);
PAINT GREEN (-5912 5233);
FORCEPROP 2 LAST CDS_LIB mstr_standard
J 0
(-5850 5225);
DISPLAY 0.723404 (-5850 5225);
PAINT MONO (-5850 5225);
DISPLAY INVISIBLE (-5850 5225);
FORCEPROP 1 LAST BODY_TYPE PLUMBING
J 0
(-5850 5275);
DISPLAY 0.872340 (-5850 5275);
PAINT GREEN (-5850 5275);
DISPLAY INVISIBLE (-5850 5275);
FORCEPROP 1 LAST HDL_TAP TRUE
J 0
(-5525 5100);
DISPLAY 0.872340 (-5525 5100);
DISPLAY INVISIBLE (-5525 5100);
FORCEPROP 1 LAST PATH I123
J 0
(-5852 5225);
DISPLAY 0.872340 (-5852 5225);
PAINT GREEN (-5852 5225);
DISPLAY INVISIBLE (-5852 5225);
FORCEADD TAP..1
(-5850 5325);
FORCEPROP 3 LASTPIN (-5900 5325) SIG_NAME M_J_CPU1_SA_DQ<31>
J 0
(-5890 5335);
DISPLAY 0.659574 (-5890 5335);
PAINT MONO (-5890 5335);
DISPLAY INVISIBLE (-5890 5335);
FORCEPROP 1 LASTPIN (-5900 5325) BN 31
J 0
(-5912 5333);
DISPLAY 0.489362 (-5912 5333);
PAINT GREEN (-5912 5333);
FORCEPROP 2 LAST CDS_LIB mstr_standard
J 0
(-5850 5325);
DISPLAY 0.723404 (-5850 5325);
PAINT MONO (-5850 5325);
DISPLAY INVISIBLE (-5850 5325);
FORCEPROP 1 LAST BODY_TYPE PLUMBING
J 0
(-5850 5375);
DISPLAY 0.872340 (-5850 5375);
PAINT GREEN (-5850 5375);
DISPLAY INVISIBLE (-5850 5375);
FORCEPROP 1 LAST HDL_TAP TRUE
J 0
(-5525 5200);
DISPLAY 0.872340 (-5525 5200);
DISPLAY INVISIBLE (-5525 5200);
FORCEPROP 1 LAST PATH I124
J 0
(-5852 5325);
DISPLAY 0.872340 (-5852 5325);
PAINT GREEN (-5852 5325);
DISPLAY INVISIBLE (-5852 5325);
FORCEADD OFFPAGE..3
(-5200 5375);
FORCEPROP 2 LAST $XR0 46 
J 0
(-4986 5375);
DISPLAY 0.638298 (-4986 5375);
PAINT MONO (-4986 5375);
FORCEPROP 2 LAST PATH I125
J 0
(-4975 5425);
DISPLAY 1.021277 (-4975 5425);
DISPLAY INVISIBLE (-4975 5425);
FORCEPROP 1 LAST COMMENT_BODY TRUE
J 0
(-5250 5275);
DISPLAY 0.872340 (-5250 5275);
PAINT GREEN (-5250 5275);
DISPLAY INVISIBLE (-5250 5275);
FORCEPROP 1 LAST OFFPAGE TRUE
J 0
(-4875 5250);
DISPLAY 0.872340 (-4875 5250);
PAINT GREEN (-4875 5250);
DISPLAY INVISIBLE (-4875 5250);
FORCEPROP 2 LAST CDS_LIB mstr_standard
J 0
(-5200 5375);
DISPLAY 0.723404 (-5200 5375);
PAINT MONO (-5200 5375);
DISPLAY INVISIBLE (-5200 5375);
FORCEADD GND..1
(-6250 950);
FORCEPROP 3 LASTPIN (-6250 1000) SIG_NAME GND\g
J 0
(-6240 1010);
DISPLAY 0.659574 (-6240 1010);
PAINT MONO (-6240 1010);
DISPLAY INVISIBLE (-6240 1010);
FORCEPROP 1 LAST SIZE 1B
J 0
(-6175 900);
DISPLAY 0.851064 (-6175 900);
PAINT GREEN (-6175 900);
DISPLAY INVISIBLE (-6175 900);
FORCEPROP 2 LAST BOM_COST MEM
J 0
(-6350 1025);
DISPLAY 0.808511 (-6350 1025);
DISPLAY INVISIBLE (-6350 1025);
FORCEPROP 2 LAST CDS_LIB mstr_symbols
J 0
(-6250 950);
DISPLAY 0.808511 (-6250 950);
DISPLAY INVISIBLE (-6250 950);
FORCEPROP 1 LAST BODY_TYPE PLUMBING
J 0
(-6295 907);
DISPLAY 0.340426 (-6295 907);
PAINT GREEN (-6295 907);
DISPLAY INVISIBLE (-6295 907);
FORCEPROP 1 LAST PATH I126
J 0
(-6175 950);
DISPLAY 0.872340 (-6175 950);
PAINT AQUA (-6175 950);
DISPLAY INVISIBLE (-6175 950);
FORCEPROP 1 LAST VOLTAGE 0.0
J 0
(-6295 907);
DISPLAY 0.723404 (-6295 907);
PAINT SKYBLUE (-6295 907);
DISPLAY INVISIBLE (-6295 907);
FORCEPROP 1 LAST HDL_POWER GND
J 0
(-6250 1100);
DISPLAY 0.851064 (-6250 1100);
PAINT GREEN (-6250 1100);
DISPLAY INVISIBLE (-6250 1100);
FORCEADD Q_RES..2
(-6250 1175);
FORCEPROP 1 LAST LOCATION R776
J 0
(-6205 1300);
DISPLAY 0.489362 (-6205 1300);
PAINT SKYBLUE (-6205 1300);
FORCEPROP 0 LAST $SEC 1
J 0
(-6200 1350);
DISPLAY 0.680851 (-6200 1350);
PAINT MONO (-6200 1350);
DISPLAY INVISIBLE (-6200 1350);
FORCEPROP 0 LAST CDS_SEC 1
J 0
(-6200 1350);
DISPLAY 1.021277 (-6200 1350);
DISPLAY INVISIBLE (-6200 1350);
FORCEPROP 1 LASTPIN (-6250 1275) $PN 1
J 0
(-6245 1237);
DISPLAY 0.489362 (-6245 1237);
PAINT MONO (-6245 1237);
FORCEPROP 1 LASTPIN (-6250 1075) $PN 2
J 0
(-6245 1085);
DISPLAY 0.489362 (-6245 1085);
PAINT MONO (-6245 1085);
FORCEPROP 1 LAST WATTAGE 1/16W
J 0
(-6210 1150);
DISPLAY 0.489362 (-6210 1150);
PAINT SKYBLUE (-6210 1150);
FORCEPROP 1 LAST MATERIAL CHIP
J 0
(-6210 1100);
DISPLAY 0.489362 (-6210 1100);
PAINT SKYBLUE (-6210 1100);
FORCEPROP 1 LAST TOLERANCE 1%
J 0
(-6205 1200);
DISPLAY 0.489362 (-6205 1200);
PAINT SKYBLUE (-6205 1200);
FORCEPROP 1 LAST VALUE 35.7K
J 0
(-6205 1250);
DISPLAY 0.489362 (-6205 1250);
PAINT SKYBLUE (-6205 1250);
FORCEPROP 1 LAST PART_NUMBER CS33572FB01
J 0
(-6210 1050);
DISPLAY 0.489362 (-6210 1050);
PAINT SKYBLUE (-6210 1050);
FORCEPROP 1 LAST PACK_TYPE 0402LF
J 0
(-6210 1000);
DISPLAY 0.489362 (-6210 1000);
PAINT SKYBLUE (-6210 1000);
FORCEPROP 2 LAST CDS_LIB pure_quanta
J 0
(-6250 1175);
DISPLAY INVISIBLE (-6250 1175);
FORCEPROP 1 LAST PATH I127
J 0
(-6200 1350);
DISPLAY 0.978723 (-6200 1350);
PAINT WHITE (-6200 1350);
DISPLAY INVISIBLE (-6200 1350);
FORCEADD GND..1
(-2025 1800);
FORCEPROP 3 LASTPIN (-2025 1850) SIG_NAME GND\g
J 0
(-2015 1860);
DISPLAY 0.659574 (-2015 1860);
PAINT MONO (-2015 1860);
DISPLAY INVISIBLE (-2015 1860);
FORCEPROP 2 LAST CDS_LIB mstr_symbols
J 0
(-2025 1800);
DISPLAY 0.723404 (-2025 1800);
DISPLAY INVISIBLE (-2025 1800);
FORCEPROP 1 LAST SIZE 1B
J 0
(-1950 1750);
DISPLAY 0.851064 (-1950 1750);
PAINT GREEN (-1950 1750);
DISPLAY INVISIBLE (-1950 1750);
FORCEPROP 1 LAST BODY_TYPE PLUMBING
J 0
(-2070 1757);
DISPLAY 0.340426 (-2070 1757);
PAINT GREEN (-2070 1757);
DISPLAY INVISIBLE (-2070 1757);
FORCEPROP 1 LAST PATH I128
J 0
(-1950 1800);
DISPLAY 0.872340 (-1950 1800);
PAINT AQUA (-1950 1800);
DISPLAY INVISIBLE (-1950 1800);
FORCEPROP 1 LAST VOLTAGE 0.0
J 0
(-2070 1757);
DISPLAY 0.723404 (-2070 1757);
PAINT SKYBLUE (-2070 1757);
DISPLAY INVISIBLE (-2070 1757);
FORCEPROP 1 LAST HDL_POWER GND
J 0
(-2025 1950);
DISPLAY 0.851064 (-2025 1950);
PAINT GREEN (-2025 1950);
DISPLAY INVISIBLE (-2025 1950);
FORCEADD OFFPAGE..5
(-7025 1350);
FORCEPROP 2 LAST $XR0 106 
J 0
(-7280 1350);
DISPLAY 0.638298 (-7280 1350);
PAINT MONO (-7280 1350);
FORCEPROP 2 LAST PATH I129
J 0
(-7275 1400);
DISPLAY 1.021277 (-7275 1400);
DISPLAY INVISIBLE (-7275 1400);
FORCEPROP 1 LAST COMMENT_BODY TRUE
J 0
(-6925 1275);
DISPLAY 0.872340 (-6925 1275);
PAINT GREEN (-6925 1275);
DISPLAY INVISIBLE (-6925 1275);
FORCEPROP 1 LAST OFFPAGE TRUE
J 0
(-6700 1225);
DISPLAY 0.872340 (-6700 1225);
PAINT GREEN (-6700 1225);
DISPLAY INVISIBLE (-6700 1225);
FORCEPROP 2 LAST BOM_COST MEM
J 0
(-7100 1425);
DISPLAY 0.808511 (-7100 1425);
DISPLAY INVISIBLE (-7100 1425);
FORCEPROP 2 LAST CDS_LIB mstr_standard
J 0
(-7025 1350);
DISPLAY 0.808511 (-7025 1350);
DISPLAY INVISIBLE (-7025 1350);
FORCEADD OFFPAGE..1
(-8150 4075);
FORCEPROP 2 LAST $XR0 46 
J 0
(-8401 4075);
DISPLAY 0.638298 (-8401 4075);
PAINT MONO (-8401 4075);
FORCEPROP 2 LAST PATH I13
J 0
(-8400 4125);
DISPLAY 1.021277 (-8400 4125);
DISPLAY INVISIBLE (-8400 4125);
FORCEPROP 1 LAST COMMENT_BODY TRUE
J 0
(-8025 3975);
DISPLAY 0.872340 (-8025 3975);
PAINT GREEN (-8025 3975);
DISPLAY INVISIBLE (-8025 3975);
FORCEPROP 1 LAST OFFPAGE TRUE
J 0
(-7825 3950);
DISPLAY 0.872340 (-7825 3950);
PAINT GREEN (-7825 3950);
DISPLAY INVISIBLE (-7825 3950);
FORCEPROP 2 LAST CDS_LIB mstr_standard
J 0
(-8150 4075);
DISPLAY 0.723404 (-8150 4075);
PAINT MONO (-8150 4075);
DISPLAY INVISIBLE (-8150 4075);
FORCEADD OFFPAGE..1
(-8150 4325);
FORCEPROP 2 LAST $XR0 46 
J 0
(-8401 4325);
DISPLAY 0.638298 (-8401 4325);
PAINT MONO (-8401 4325);
FORCEPROP 2 LAST PATH I14
J 0
(-8400 4375);
DISPLAY 1.021277 (-8400 4375);
DISPLAY INVISIBLE (-8400 4375);
FORCEPROP 1 LAST COMMENT_BODY TRUE
J 0
(-8025 4225);
DISPLAY 0.872340 (-8025 4225);
PAINT GREEN (-8025 4225);
DISPLAY INVISIBLE (-8025 4225);
FORCEPROP 1 LAST OFFPAGE TRUE
J 0
(-7825 4200);
DISPLAY 0.872340 (-7825 4200);
PAINT GREEN (-7825 4200);
DISPLAY INVISIBLE (-7825 4200);
FORCEPROP 2 LAST CDS_LIB mstr_standard
J 0
(-8150 4325);
DISPLAY 0.808511 (-8150 4325);
DISPLAY INVISIBLE (-8150 4325);
FORCEADD GND..1
(-225 1575);
FORCEPROP 3 LASTPIN (-225 1625) SIG_NAME GND\g
J 0
(-215 1635);
DISPLAY 0.659574 (-215 1635);
PAINT MONO (-215 1635);
DISPLAY INVISIBLE (-215 1635);
FORCEPROP 2 LAST CDS_LIB mstr_symbols
J 0
(-225 1575);
DISPLAY 0.723404 (-225 1575);
DISPLAY INVISIBLE (-225 1575);
FORCEPROP 1 LAST SIZE 1B
J 0
(-150 1525);
DISPLAY 0.851064 (-150 1525);
PAINT GREEN (-150 1525);
DISPLAY INVISIBLE (-150 1525);
FORCEPROP 1 LAST BODY_TYPE PLUMBING
J 0
(-270 1532);
DISPLAY 0.340426 (-270 1532);
PAINT GREEN (-270 1532);
DISPLAY INVISIBLE (-270 1532);
FORCEPROP 1 LAST PATH I142
J 0
(-150 1575);
DISPLAY 0.872340 (-150 1575);
PAINT AQUA (-150 1575);
DISPLAY INVISIBLE (-150 1575);
FORCEPROP 1 LAST VOLTAGE 0.0
J 0
(-270 1532);
DISPLAY 0.723404 (-270 1532);
PAINT SKYBLUE (-270 1532);
DISPLAY INVISIBLE (-270 1532);
FORCEPROP 1 LAST HDL_POWER GND
J 0
(-225 1725);
DISPLAY 0.851064 (-225 1725);
PAINT GREEN (-225 1725);
DISPLAY INVISIBLE (-225 1725);
FORCEADD SCONN288_DDR506112002KQ..3
(-1125 3575);
FORCEPROP 1 LAST LOCATION J29
J 0
(-1575 5550);
DISPLAY 0.468085 (-1575 5550);
PAINT SKYBLUE (-1575 5550);
FORCEPROP 0 LAST $SEC 3
J 0
(-1575 5700);
DISPLAY 0.680851 (-1575 5700);
PAINT MONO (-1575 5700);
DISPLAY INVISIBLE (-1575 5700);
FORCEPROP 2 LAST CDS_SEC 3
J 0
(-1575 5700);
DISPLAY 1.021277 (-1575 5700);
DISPLAY INVISIBLE (-1575 5700);
FORCEPROP 0 LASTPIN (-525 1975) $PN G1
J 0
(-515 1985);
DISPLAY 0.680851 (-515 1985);
PAINT MONO (-515 1985);
FORCEPROP 0 LASTPIN (-525 1925) $PN G2
J 0
(-515 1935);
DISPLAY 0.680851 (-515 1935);
PAINT MONO (-515 1935);
FORCEPROP 0 LASTPIN (-525 1875) $PN G3
J 0
(-515 1885);
DISPLAY 0.680851 (-515 1885);
PAINT MONO (-515 1885);
FORCEPROP 0 LASTPIN (-1725 5125) $PN 1
J 2
(-1735 5135);
DISPLAY 0.680851 (-1735 5135);
PAINT MONO (-1735 5135);
FORCEPROP 0 LASTPIN (-1725 5175) $PN 145
J 2
(-1735 5185);
DISPLAY 0.680851 (-1735 5185);
PAINT MONO (-1735 5185);
FORCEPROP 0 LASTPIN (-1725 5225) $PN 146
J 2
(-1735 5235);
DISPLAY 0.680851 (-1735 5235);
PAINT MONO (-1735 5235);
FORCEPROP 0 LASTPIN (-525 2075) $PN 6
J 0
(-515 2085);
DISPLAY 0.680851 (-515 2085);
PAINT MONO (-515 2085);
FORCEPROP 0 LASTPIN (-525 2125) $PN 8
J 0
(-515 2135);
DISPLAY 0.680851 (-515 2135);
PAINT MONO (-515 2135);
FORCEPROP 0 LASTPIN (-525 2175) $PN 10
J 0
(-515 2185);
DISPLAY 0.680851 (-515 2185);
PAINT MONO (-515 2185);
FORCEPROP 0 LASTPIN (-525 2225) $PN 13
J 0
(-515 2235);
DISPLAY 0.680851 (-515 2235);
PAINT MONO (-515 2235);
FORCEPROP 0 LASTPIN (-525 2275) $PN 15
J 0
(-515 2285);
DISPLAY 0.680851 (-515 2285);
PAINT MONO (-515 2285);
FORCEPROP 0 LASTPIN (-525 2325) $PN 17
J 0
(-515 2335);
DISPLAY 0.680851 (-515 2335);
PAINT MONO (-515 2335);
FORCEPROP 0 LASTPIN (-525 2375) $PN 19
J 0
(-515 2385);
DISPLAY 0.680851 (-515 2385);
PAINT MONO (-515 2385);
FORCEPROP 0 LASTPIN (-525 2425) $PN 21
J 0
(-515 2435);
DISPLAY 0.680851 (-515 2435);
PAINT MONO (-515 2435);
FORCEPROP 0 LASTPIN (-525 2475) $PN 24
J 0
(-515 2485);
DISPLAY 0.680851 (-515 2485);
PAINT MONO (-515 2485);
FORCEPROP 0 LASTPIN (-525 2525) $PN 26
J 0
(-515 2535);
DISPLAY 0.680851 (-515 2535);
PAINT MONO (-515 2535);
FORCEPROP 0 LASTPIN (-525 2575) $PN 28
J 0
(-515 2585);
DISPLAY 0.680851 (-515 2585);
PAINT MONO (-515 2585);
FORCEPROP 0 LASTPIN (-525 2625) $PN 30
J 0
(-515 2635);
DISPLAY 0.680851 (-515 2635);
PAINT MONO (-515 2635);
FORCEPROP 0 LASTPIN (-525 2675) $PN 32
J 0
(-515 2685);
DISPLAY 0.680851 (-515 2685);
PAINT MONO (-515 2685);
FORCEPROP 0 LASTPIN (-525 2725) $PN 35
J 0
(-515 2735);
DISPLAY 0.680851 (-515 2735);
PAINT MONO (-515 2735);
FORCEPROP 0 LASTPIN (-525 2775) $PN 37
J 0
(-515 2785);
DISPLAY 0.680851 (-515 2785);
PAINT MONO (-515 2785);
FORCEPROP 0 LASTPIN (-525 2825) $PN 39
J 0
(-515 2835);
DISPLAY 0.680851 (-515 2835);
PAINT MONO (-515 2835);
FORCEPROP 0 LASTPIN (-525 2875) $PN 41
J 0
(-515 2885);
DISPLAY 0.680851 (-515 2885);
PAINT MONO (-515 2885);
FORCEPROP 0 LASTPIN (-525 2925) $PN 43
J 0
(-515 2935);
DISPLAY 0.680851 (-515 2935);
PAINT MONO (-515 2935);
FORCEPROP 0 LASTPIN (-525 2975) $PN 46
J 0
(-515 2985);
DISPLAY 0.680851 (-515 2985);
PAINT MONO (-515 2985);
FORCEPROP 0 LASTPIN (-525 3025) $PN 48
J 0
(-515 3035);
DISPLAY 0.680851 (-515 3035);
PAINT MONO (-515 3035);
FORCEPROP 0 LASTPIN (-525 3075) $PN 50
J 0
(-515 3085);
DISPLAY 0.680851 (-515 3085);
PAINT MONO (-515 3085);
FORCEPROP 0 LASTPIN (-525 3125) $PN 52
J 0
(-515 3135);
DISPLAY 0.680851 (-515 3135);
PAINT MONO (-515 3135);
FORCEPROP 0 LASTPIN (-525 3175) $PN 54
J 0
(-515 3185);
DISPLAY 0.680851 (-515 3185);
PAINT MONO (-515 3185);
FORCEPROP 0 LASTPIN (-525 3225) $PN 57
J 0
(-515 3235);
DISPLAY 0.680851 (-515 3235);
PAINT MONO (-515 3235);
FORCEPROP 0 LASTPIN (-525 3275) $PN 59
J 0
(-515 3285);
DISPLAY 0.680851 (-515 3285);
PAINT MONO (-515 3285);
FORCEPROP 0 LASTPIN (-525 3325) $PN 61
J 0
(-515 3335);
DISPLAY 0.680851 (-515 3335);
PAINT MONO (-515 3335);
FORCEPROP 0 LASTPIN (-525 3375) $PN 63
J 0
(-515 3385);
DISPLAY 0.680851 (-515 3385);
PAINT MONO (-515 3385);
FORCEPROP 0 LASTPIN (-525 3425) $PN 65
J 0
(-515 3435);
DISPLAY 0.680851 (-515 3435);
PAINT MONO (-515 3435);
FORCEPROP 0 LASTPIN (-525 3475) $PN 67
J 0
(-515 3485);
DISPLAY 0.680851 (-515 3485);
PAINT MONO (-515 3485);
FORCEPROP 0 LASTPIN (-525 3525) $PN 69
J 0
(-515 3535);
DISPLAY 0.680851 (-515 3535);
PAINT MONO (-515 3535);
FORCEPROP 0 LASTPIN (-525 3575) $PN 71
J 0
(-515 3585);
DISPLAY 0.680851 (-515 3585);
PAINT MONO (-515 3585);
FORCEPROP 0 LASTPIN (-525 3625) $PN 73
J 0
(-515 3635);
DISPLAY 0.680851 (-515 3635);
PAINT MONO (-515 3635);
FORCEPROP 0 LASTPIN (-525 3675) $PN 75
J 0
(-515 3685);
DISPLAY 0.680851 (-515 3685);
PAINT MONO (-515 3685);
FORCEPROP 0 LASTPIN (-525 3725) $PN 77
J 0
(-515 3735);
DISPLAY 0.680851 (-515 3735);
PAINT MONO (-515 3735);
FORCEPROP 0 LASTPIN (-525 3775) $PN 79
J 0
(-515 3785);
DISPLAY 0.680851 (-515 3785);
PAINT MONO (-515 3785);
FORCEPROP 0 LASTPIN (-525 3825) $PN 81
J 0
(-515 3835);
DISPLAY 0.680851 (-515 3835);
PAINT MONO (-515 3835);
FORCEPROP 0 LASTPIN (-525 3875) $PN 83
J 0
(-515 3885);
DISPLAY 0.680851 (-515 3885);
PAINT MONO (-515 3885);
FORCEPROP 0 LASTPIN (-525 3925) $PN 85
J 0
(-515 3935);
DISPLAY 0.680851 (-515 3935);
PAINT MONO (-515 3935);
FORCEPROP 0 LASTPIN (-525 3975) $PN 88
J 0
(-515 3985);
DISPLAY 0.680851 (-515 3985);
PAINT MONO (-515 3985);
FORCEPROP 0 LASTPIN (-525 4025) $PN 90
J 0
(-515 4035);
DISPLAY 0.680851 (-515 4035);
PAINT MONO (-515 4035);
FORCEPROP 0 LASTPIN (-525 4075) $PN 92
J 0
(-515 4085);
DISPLAY 0.680851 (-515 4085);
PAINT MONO (-515 4085);
FORCEPROP 0 LASTPIN (-525 4125) $PN 95
J 0
(-515 4135);
DISPLAY 0.680851 (-515 4135);
PAINT MONO (-515 4135);
FORCEPROP 0 LASTPIN (-525 4175) $PN 97
J 0
(-515 4185);
DISPLAY 0.680851 (-515 4185);
PAINT MONO (-515 4185);
FORCEPROP 0 LASTPIN (-525 4225) $PN 99
J 0
(-515 4235);
DISPLAY 0.680851 (-515 4235);
PAINT MONO (-515 4235);
FORCEPROP 0 LASTPIN (-525 4275) $PN 101
J 0
(-515 4285);
DISPLAY 0.680851 (-515 4285);
PAINT MONO (-515 4285);
FORCEPROP 0 LASTPIN (-525 4325) $PN 103
J 0
(-515 4335);
DISPLAY 0.680851 (-515 4335);
PAINT MONO (-515 4335);
FORCEPROP 0 LASTPIN (-525 4375) $PN 106
J 0
(-515 4385);
DISPLAY 0.680851 (-515 4385);
PAINT MONO (-515 4385);
FORCEPROP 0 LASTPIN (-525 4425) $PN 108
J 0
(-515 4435);
DISPLAY 0.680851 (-515 4435);
PAINT MONO (-515 4435);
FORCEPROP 0 LASTPIN (-525 4475) $PN 110
J 0
(-515 4485);
DISPLAY 0.680851 (-515 4485);
PAINT MONO (-515 4485);
FORCEPROP 0 LASTPIN (-525 4525) $PN 112
J 0
(-515 4535);
DISPLAY 0.680851 (-515 4535);
PAINT MONO (-515 4535);
FORCEPROP 0 LASTPIN (-525 4575) $PN 114
J 0
(-515 4585);
DISPLAY 0.680851 (-515 4585);
PAINT MONO (-515 4585);
FORCEPROP 0 LASTPIN (-525 4625) $PN 117
J 0
(-515 4635);
DISPLAY 0.680851 (-515 4635);
PAINT MONO (-515 4635);
FORCEPROP 0 LASTPIN (-525 4675) $PN 119
J 0
(-515 4685);
DISPLAY 0.680851 (-515 4685);
PAINT MONO (-515 4685);
FORCEPROP 0 LASTPIN (-525 4725) $PN 121
J 0
(-515 4735);
DISPLAY 0.680851 (-515 4735);
PAINT MONO (-515 4735);
FORCEPROP 0 LASTPIN (-525 4775) $PN 123
J 0
(-515 4785);
DISPLAY 0.680851 (-515 4785);
PAINT MONO (-515 4785);
FORCEPROP 0 LASTPIN (-525 4825) $PN 125
J 0
(-515 4835);
DISPLAY 0.680851 (-515 4835);
PAINT MONO (-515 4835);
FORCEPROP 0 LASTPIN (-525 4875) $PN 128
J 0
(-515 4885);
DISPLAY 0.680851 (-515 4885);
PAINT MONO (-515 4885);
FORCEPROP 0 LASTPIN (-525 4925) $PN 130
J 0
(-515 4935);
DISPLAY 0.680851 (-515 4935);
PAINT MONO (-515 4935);
FORCEPROP 0 LASTPIN (-525 4975) $PN 132
J 0
(-515 4985);
DISPLAY 0.680851 (-515 4985);
PAINT MONO (-515 4985);
FORCEPROP 0 LASTPIN (-525 5025) $PN 134
J 0
(-515 5035);
DISPLAY 0.680851 (-515 5035);
PAINT MONO (-515 5035);
FORCEPROP 0 LASTPIN (-525 5075) $PN 136
J 0
(-515 5085);
DISPLAY 0.680851 (-515 5085);
PAINT MONO (-515 5085);
FORCEPROP 0 LASTPIN (-525 5125) $PN 139
J 0
(-515 5135);
DISPLAY 0.680851 (-515 5135);
PAINT MONO (-515 5135);
FORCEPROP 0 LASTPIN (-525 5175) $PN 141
J 0
(-515 5185);
DISPLAY 0.680851 (-515 5185);
PAINT MONO (-515 5185);
FORCEPROP 0 LASTPIN (-525 5225) $PN 143
J 0
(-515 5235);
DISPLAY 0.680851 (-515 5235);
PAINT MONO (-515 5235);
FORCEPROP 0 LASTPIN (-1725 1975) $PN 151
J 2
(-1735 1985);
DISPLAY 0.680851 (-1735 1985);
PAINT MONO (-1735 1985);
FORCEPROP 0 LASTPIN (-1725 2025) $PN 153
J 2
(-1735 2035);
DISPLAY 0.680851 (-1735 2035);
PAINT MONO (-1735 2035);
FORCEPROP 0 LASTPIN (-1725 2075) $PN 155
J 2
(-1735 2085);
DISPLAY 0.680851 (-1735 2085);
PAINT MONO (-1735 2085);
FORCEPROP 0 LASTPIN (-1725 2125) $PN 158
J 2
(-1735 2135);
DISPLAY 0.680851 (-1735 2135);
PAINT MONO (-1735 2135);
FORCEPROP 0 LASTPIN (-1725 2175) $PN 160
J 2
(-1735 2185);
DISPLAY 0.680851 (-1735 2185);
PAINT MONO (-1735 2185);
FORCEPROP 0 LASTPIN (-1725 2225) $PN 162
J 2
(-1735 2235);
DISPLAY 0.680851 (-1735 2235);
PAINT MONO (-1735 2235);
FORCEPROP 0 LASTPIN (-1725 2275) $PN 164
J 2
(-1735 2285);
DISPLAY 0.680851 (-1735 2285);
PAINT MONO (-1735 2285);
FORCEPROP 0 LASTPIN (-1725 2325) $PN 166
J 2
(-1735 2335);
DISPLAY 0.680851 (-1735 2335);
PAINT MONO (-1735 2335);
FORCEPROP 0 LASTPIN (-1725 2375) $PN 169
J 2
(-1735 2385);
DISPLAY 0.680851 (-1735 2385);
PAINT MONO (-1735 2385);
FORCEPROP 0 LASTPIN (-1725 2425) $PN 171
J 2
(-1735 2435);
DISPLAY 0.680851 (-1735 2435);
PAINT MONO (-1735 2435);
FORCEPROP 0 LASTPIN (-1725 2475) $PN 173
J 2
(-1735 2485);
DISPLAY 0.680851 (-1735 2485);
PAINT MONO (-1735 2485);
FORCEPROP 0 LASTPIN (-1725 2525) $PN 175
J 2
(-1735 2535);
DISPLAY 0.680851 (-1735 2535);
PAINT MONO (-1735 2535);
FORCEPROP 0 LASTPIN (-1725 2575) $PN 177
J 2
(-1735 2585);
DISPLAY 0.680851 (-1735 2585);
PAINT MONO (-1735 2585);
FORCEPROP 0 LASTPIN (-1725 2625) $PN 180
J 2
(-1735 2635);
DISPLAY 0.680851 (-1735 2635);
PAINT MONO (-1735 2635);
FORCEPROP 0 LASTPIN (-1725 2675) $PN 182
J 2
(-1735 2685);
DISPLAY 0.680851 (-1735 2685);
PAINT MONO (-1735 2685);
FORCEPROP 0 LASTPIN (-1725 2725) $PN 184
J 2
(-1735 2735);
DISPLAY 0.680851 (-1735 2735);
PAINT MONO (-1735 2735);
FORCEPROP 0 LASTPIN (-1725 2775) $PN 186
J 2
(-1735 2785);
DISPLAY 0.680851 (-1735 2785);
PAINT MONO (-1735 2785);
FORCEPROP 0 LASTPIN (-1725 2825) $PN 188
J 2
(-1735 2835);
DISPLAY 0.680851 (-1735 2835);
PAINT MONO (-1735 2835);
FORCEPROP 0 LASTPIN (-1725 2875) $PN 191
J 2
(-1735 2885);
DISPLAY 0.680851 (-1735 2885);
PAINT MONO (-1735 2885);
FORCEPROP 0 LASTPIN (-1725 2925) $PN 193
J 2
(-1735 2935);
DISPLAY 0.680851 (-1735 2935);
PAINT MONO (-1735 2935);
FORCEPROP 0 LASTPIN (-1725 2975) $PN 195
J 2
(-1735 2985);
DISPLAY 0.680851 (-1735 2985);
PAINT MONO (-1735 2985);
FORCEPROP 0 LASTPIN (-1725 3025) $PN 197
J 2
(-1735 3035);
DISPLAY 0.680851 (-1735 3035);
PAINT MONO (-1735 3035);
FORCEPROP 0 LASTPIN (-1725 3075) $PN 199
J 2
(-1735 3085);
DISPLAY 0.680851 (-1735 3085);
PAINT MONO (-1735 3085);
FORCEPROP 0 LASTPIN (-1725 3125) $PN 202
J 2
(-1735 3135);
DISPLAY 0.680851 (-1735 3135);
PAINT MONO (-1735 3135);
FORCEPROP 0 LASTPIN (-1725 3175) $PN 204
J 2
(-1735 3185);
DISPLAY 0.680851 (-1735 3185);
PAINT MONO (-1735 3185);
FORCEPROP 0 LASTPIN (-1725 3225) $PN 206
J 2
(-1735 3235);
DISPLAY 0.680851 (-1735 3235);
PAINT MONO (-1735 3235);
FORCEPROP 0 LASTPIN (-1725 3275) $PN 208
J 2
(-1735 3285);
DISPLAY 0.680851 (-1735 3285);
PAINT MONO (-1735 3285);
FORCEPROP 0 LASTPIN (-1725 3325) $PN 210
J 2
(-1735 3335);
DISPLAY 0.680851 (-1735 3335);
PAINT MONO (-1735 3335);
FORCEPROP 0 LASTPIN (-1725 3375) $PN 212
J 2
(-1735 3385);
DISPLAY 0.680851 (-1735 3385);
PAINT MONO (-1735 3385);
FORCEPROP 0 LASTPIN (-1725 3425) $PN 214
J 2
(-1735 3435);
DISPLAY 0.680851 (-1735 3435);
PAINT MONO (-1735 3435);
FORCEPROP 0 LASTPIN (-1725 3475) $PN 216
J 2
(-1735 3485);
DISPLAY 0.680851 (-1735 3485);
PAINT MONO (-1735 3485);
FORCEPROP 0 LASTPIN (-1725 3525) $PN 219
J 2
(-1735 3535);
DISPLAY 0.680851 (-1735 3535);
PAINT MONO (-1735 3535);
FORCEPROP 0 LASTPIN (-1725 3575) $PN 222
J 2
(-1735 3585);
DISPLAY 0.680851 (-1735 3585);
PAINT MONO (-1735 3585);
FORCEPROP 0 LASTPIN (-1725 3625) $PN 224
J 2
(-1735 3635);
DISPLAY 0.680851 (-1735 3635);
PAINT MONO (-1735 3635);
FORCEPROP 0 LASTPIN (-1725 3675) $PN 226
J 2
(-1735 3685);
DISPLAY 0.680851 (-1735 3685);
PAINT MONO (-1735 3685);
FORCEPROP 0 LASTPIN (-1725 3725) $PN 228
J 2
(-1735 3735);
DISPLAY 0.680851 (-1735 3735);
PAINT MONO (-1735 3735);
FORCEPROP 0 LASTPIN (-1725 3775) $PN 230
J 2
(-1735 3785);
DISPLAY 0.680851 (-1735 3785);
PAINT MONO (-1735 3785);
FORCEPROP 0 LASTPIN (-1725 3825) $PN 233
J 2
(-1735 3835);
DISPLAY 0.680851 (-1735 3835);
PAINT MONO (-1735 3835);
FORCEPROP 0 LASTPIN (-1725 3875) $PN 235
J 2
(-1735 3885);
DISPLAY 0.680851 (-1735 3885);
PAINT MONO (-1735 3885);
FORCEPROP 0 LASTPIN (-1725 3925) $PN 237
J 2
(-1735 3935);
DISPLAY 0.680851 (-1735 3935);
PAINT MONO (-1735 3935);
FORCEPROP 0 LASTPIN (-1725 3975) $PN 240
J 2
(-1735 3985);
DISPLAY 0.680851 (-1735 3985);
PAINT MONO (-1735 3985);
FORCEPROP 0 LASTPIN (-1725 4025) $PN 242
J 2
(-1735 4035);
DISPLAY 0.680851 (-1735 4035);
PAINT MONO (-1735 4035);
FORCEPROP 0 LASTPIN (-1725 4075) $PN 244
J 2
(-1735 4085);
DISPLAY 0.680851 (-1735 4085);
PAINT MONO (-1735 4085);
FORCEPROP 0 LASTPIN (-1725 4125) $PN 246
J 2
(-1735 4135);
DISPLAY 0.680851 (-1735 4135);
PAINT MONO (-1735 4135);
FORCEPROP 0 LASTPIN (-1725 4175) $PN 248
J 2
(-1735 4185);
DISPLAY 0.680851 (-1735 4185);
PAINT MONO (-1735 4185);
FORCEPROP 0 LASTPIN (-1725 4225) $PN 251
J 2
(-1735 4235);
DISPLAY 0.680851 (-1735 4235);
PAINT MONO (-1735 4235);
FORCEPROP 0 LASTPIN (-1725 4275) $PN 253
J 2
(-1735 4285);
DISPLAY 0.680851 (-1735 4285);
PAINT MONO (-1735 4285);
FORCEPROP 0 LASTPIN (-1725 4325) $PN 255
J 2
(-1735 4335);
DISPLAY 0.680851 (-1735 4335);
PAINT MONO (-1735 4335);
FORCEPROP 0 LASTPIN (-1725 4375) $PN 257
J 2
(-1735 4385);
DISPLAY 0.680851 (-1735 4385);
PAINT MONO (-1735 4385);
FORCEPROP 0 LASTPIN (-1725 4425) $PN 259
J 2
(-1735 4435);
DISPLAY 0.680851 (-1735 4435);
PAINT MONO (-1735 4435);
FORCEPROP 0 LASTPIN (-1725 4475) $PN 262
J 2
(-1735 4485);
DISPLAY 0.680851 (-1735 4485);
PAINT MONO (-1735 4485);
FORCEPROP 0 LASTPIN (-1725 4525) $PN 264
J 2
(-1735 4535);
DISPLAY 0.680851 (-1735 4535);
PAINT MONO (-1735 4535);
FORCEPROP 0 LASTPIN (-1725 4575) $PN 266
J 2
(-1735 4585);
DISPLAY 0.680851 (-1735 4585);
PAINT MONO (-1735 4585);
FORCEPROP 0 LASTPIN (-1725 4625) $PN 268
J 2
(-1735 4635);
DISPLAY 0.680851 (-1735 4635);
PAINT MONO (-1735 4635);
FORCEPROP 0 LASTPIN (-1725 4675) $PN 270
J 2
(-1735 4685);
DISPLAY 0.680851 (-1735 4685);
PAINT MONO (-1735 4685);
FORCEPROP 0 LASTPIN (-1725 4725) $PN 273
J 2
(-1735 4735);
DISPLAY 0.680851 (-1735 4735);
PAINT MONO (-1735 4735);
FORCEPROP 0 LASTPIN (-1725 4775) $PN 275
J 2
(-1735 4785);
DISPLAY 0.680851 (-1735 4785);
PAINT MONO (-1735 4785);
FORCEPROP 0 LASTPIN (-1725 4825) $PN 277
J 2
(-1735 4835);
DISPLAY 0.680851 (-1735 4835);
PAINT MONO (-1735 4835);
FORCEPROP 0 LASTPIN (-1725 4875) $PN 279
J 2
(-1735 4885);
DISPLAY 0.680851 (-1735 4885);
PAINT MONO (-1735 4885);
FORCEPROP 0 LASTPIN (-1725 4925) $PN 281
J 2
(-1735 4935);
DISPLAY 0.680851 (-1735 4935);
PAINT MONO (-1735 4935);
FORCEPROP 0 LASTPIN (-1725 4975) $PN 284
J 2
(-1735 4985);
DISPLAY 0.680851 (-1735 4985);
PAINT MONO (-1735 4985);
FORCEPROP 0 LASTPIN (-1725 5025) $PN 286
J 2
(-1735 5035);
DISPLAY 0.680851 (-1735 5035);
PAINT MONO (-1735 5035);
FORCEPROP 0 LASTPIN (-1725 5075) $PN 288
J 2
(-1735 5085);
DISPLAY 0.680851 (-1735 5085);
PAINT MONO (-1735 5085);
FORCEPROP 2 LAST PART_TYPE SMLF
J 0
(-1575 5650);
DISPLAY 1.021277 (-1575 5650);
FORCEPROP 2 LAST VALUE SCONN288_DDR506112002KQ
J 0
(-1575 5600);
DISPLAY 0.489362 (-1575 5600);
PAINT SKYBLUE (-1575 5600);
FORCEPROP 1 LAST MATERIAL IO
J 0
(-1575 5400);
DISPLAY 0.468085 (-1575 5400);
PAINT SKYBLUE (-1575 5400);
FORCEPROP 1 LAST PART_NUMBER DFHST8FS479
J 0
(-1575 5475);
DISPLAY 0.468085 (-1575 5475);
PAINT SKYBLUE (-1575 5475);
FORCEPROP 1 LAST CDS_LMAN_SYM_OUTLINE -450,1800,450,-1750
J 0
(-1125 3575);
DISPLAY 0.468085 (-1125 3575);
PAINT GREEN (-1125 3575);
DISPLAY INVISIBLE (-1125 3575);
FORCEPROP 1 LAST PATH I143
J 0
(-1125 3575);
DISPLAY 0.723404 (-1125 3575);
PAINT GREEN (-1125 3575);
DISPLAY INVISIBLE (-1125 3575);
FORCEPROP 1 LAST NEEDS_NO_SIZE TRUE
J 0
(-1125 3575);
DISPLAY 0.723404 (-1125 3575);
PAINT GREEN (-1125 3575);
DISPLAY INVISIBLE (-1125 3575);
FORCEPROP 2 LAST CDS_LIB pure_quanta
J 0
(-1125 3575);
DISPLAY INVISIBLE (-1125 3575);
FORCEADD OFFPAGE..1
(-8150 4175);
FORCEPROP 2 LAST $XR0 46 
J 0
(-8401 4175);
DISPLAY 0.638298 (-8401 4175);
PAINT MONO (-8401 4175);
FORCEPROP 2 LAST PATH I15
J 0
(-8400 4225);
DISPLAY 1.021277 (-8400 4225);
DISPLAY INVISIBLE (-8400 4225);
FORCEPROP 1 LAST COMMENT_BODY TRUE
J 0
(-8025 4075);
DISPLAY 0.872340 (-8025 4075);
PAINT GREEN (-8025 4075);
DISPLAY INVISIBLE (-8025 4075);
FORCEPROP 1 LAST OFFPAGE TRUE
J 0
(-7825 4050);
DISPLAY 0.872340 (-7825 4050);
PAINT GREEN (-7825 4050);
DISPLAY INVISIBLE (-7825 4050);
FORCEPROP 2 LAST CDS_LIB mstr_standard
J 0
(-8150 4175);
DISPLAY 0.808511 (-8150 4175);
DISPLAY INVISIBLE (-8150 4175);
FORCEADD OFFPAGE..1
(-8150 4225);
FORCEPROP 2 LAST $XR0 46 
J 0
(-8401 4225);
DISPLAY 0.638298 (-8401 4225);
PAINT MONO (-8401 4225);
FORCEPROP 2 LAST PATH I16
J 0
(-8400 4275);
DISPLAY 1.021277 (-8400 4275);
DISPLAY INVISIBLE (-8400 4275);
FORCEPROP 1 LAST COMMENT_BODY TRUE
J 0
(-8025 4125);
DISPLAY 0.872340 (-8025 4125);
PAINT GREEN (-8025 4125);
DISPLAY INVISIBLE (-8025 4125);
FORCEPROP 1 LAST OFFPAGE TRUE
J 0
(-7825 4100);
DISPLAY 0.872340 (-7825 4100);
PAINT GREEN (-7825 4100);
DISPLAY INVISIBLE (-7825 4100);
FORCEPROP 2 LAST CDS_LIB mstr_standard
J 0
(-8150 4225);
DISPLAY 0.723404 (-8150 4225);
PAINT MONO (-8150 4225);
DISPLAY INVISIBLE (-8150 4225);
FORCEADD OFFPAGE..1
(-8150 4375);
FORCEPROP 2 LAST $XR0 46 
J 0
(-8401 4375);
DISPLAY 0.638298 (-8401 4375);
PAINT MONO (-8401 4375);
FORCEPROP 2 LAST PATH I17
J 0
(-8400 4425);
DISPLAY 1.021277 (-8400 4425);
DISPLAY INVISIBLE (-8400 4425);
FORCEPROP 1 LAST COMMENT_BODY TRUE
J 0
(-8025 4275);
DISPLAY 0.872340 (-8025 4275);
PAINT GREEN (-8025 4275);
DISPLAY INVISIBLE (-8025 4275);
FORCEPROP 1 LAST OFFPAGE TRUE
J 0
(-7825 4250);
DISPLAY 0.872340 (-7825 4250);
PAINT GREEN (-7825 4250);
DISPLAY INVISIBLE (-7825 4250);
FORCEPROP 2 LAST CDS_LIB mstr_standard
J 0
(-8150 4375);
DISPLAY 0.723404 (-8150 4375);
PAINT MONO (-8150 4375);
DISPLAY INVISIBLE (-8150 4375);
FORCEADD OFFPAGE..6
(-8150 2775);
FORCEPROP 2 LAST $XR5 136 
J 0
(-9060 2775);
DISPLAY 0.638298 (-9060 2775);
PAINT MONO (-9060 2775);
FORCEPROP 2 LAST $XR4 108 
J 0
(-8940 2775);
DISPLAY 0.638298 (-8940 2775);
PAINT MONO (-8940 2775);
FORCEPROP 2 LAST $XR3 107 
J 0
(-8820 2775);
DISPLAY 0.638298 (-8820 2775);
PAINT MONO (-8820 2775);
FORCEPROP 2 LAST $XR2 105 
J 0
(-8700 2775);
DISPLAY 0.638298 (-8700 2775);
PAINT MONO (-8700 2775);
FORCEPROP 2 LAST $XR1 104 
J 0
(-8580 2775);
DISPLAY 0.638298 (-8580 2775);
PAINT MONO (-8580 2775);
FORCEPROP 2 LAST $XR0 103 
J 0
(-8460 2775);
DISPLAY 0.638298 (-8460 2775);
PAINT MONO (-8460 2775);
FORCEPROP 2 LAST PATH I179
J 0
(-8450 2825);
DISPLAY 1.021277 (-8450 2825);
DISPLAY INVISIBLE (-8450 2825);
FORCEPROP 1 LAST COMMENT_BODY TRUE
J 0
(-8050 2700);
DISPLAY 0.872340 (-8050 2700);
PAINT GREEN (-8050 2700);
DISPLAY INVISIBLE (-8050 2700);
FORCEPROP 1 LAST OFFPAGE TRUE
J 0
(-7825 2650);
DISPLAY 0.872340 (-7825 2650);
PAINT GREEN (-7825 2650);
DISPLAY INVISIBLE (-7825 2650);
FORCEPROP 2 LAST CDS_LIB mstr_standard
J 0
(-8150 2775);
DISPLAY 0.808511 (-8150 2775);
DISPLAY INVISIBLE (-8150 2775);
FORCEADD OFFPAGE..1
(-8150 4525);
FORCEPROP 2 LAST $XR0 46 
J 0
(-8401 4525);
DISPLAY 0.638298 (-8401 4525);
PAINT MONO (-8401 4525);
FORCEPROP 2 LAST PATH I18
J 0
(-8400 4575);
DISPLAY 1.021277 (-8400 4575);
DISPLAY INVISIBLE (-8400 4575);
FORCEPROP 1 LAST COMMENT_BODY TRUE
J 0
(-8025 4425);
DISPLAY 0.872340 (-8025 4425);
PAINT GREEN (-8025 4425);
DISPLAY INVISIBLE (-8025 4425);
FORCEPROP 1 LAST OFFPAGE TRUE
J 0
(-7825 4400);
DISPLAY 0.872340 (-7825 4400);
PAINT GREEN (-7825 4400);
DISPLAY INVISIBLE (-7825 4400);
FORCEPROP 2 LAST CDS_LIB mstr_standard
J 0
(-8150 4525);
DISPLAY 0.723404 (-8150 4525);
PAINT MONO (-8150 4525);
DISPLAY INVISIBLE (-8150 4525);
FORCEADD Q_CAP..1
R 2
(-8525 3150);
FORCEPROP 1 LAST LOCATION C172
J 2
(-8575 3250);
DISPLAY 0.489362 (-8575 3250);
PAINT SKYBLUE (-8575 3250);
FORCEPROP 0 LAST $SEC 1
J 0
(-8575 3300);
DISPLAY 0.680851 (-8575 3300);
PAINT MONO (-8575 3300);
DISPLAY INVISIBLE (-8575 3300);
FORCEPROP 0 LAST CDS_SEC 1
J 0
(-8575 3300);
DISPLAY 1.021277 (-8575 3300);
DISPLAY INVISIBLE (-8575 3300);
FORCEPROP 1 LASTPIN (-8525 3250) $PN 1
J 2
(-8535 3230);
DISPLAY 0.489362 (-8535 3230);
PAINT MONO (-8535 3230);
FORCEPROP 1 LASTPIN (-8525 3050) $PN 2
J 2
(-8535 3030);
DISPLAY 0.489362 (-8535 3030);
PAINT MONO (-8535 3030);
FORCEPROP 1 LAST MATERIAL X7R
J 2
(-8575 3050);
DISPLAY 0.489362 (-8575 3050);
PAINT SKYBLUE (-8575 3050);
FORCEPROP 1 LAST TOLERANCE 10%
J 2
(-8575 3100);
DISPLAY 0.489362 (-8575 3100);
PAINT SKYBLUE (-8575 3100);
FORCEPROP 1 LAST VALUE 0.1UF
J 2
(-8575 3200);
DISPLAY 0.489362 (-8575 3200);
PAINT SKYBLUE (-8575 3200);
FORCEPROP 1 LAST PART_NUMBER CH4104K1B00
J 2
(-8575 3000);
DISPLAY 0.489362 (-8575 3000);
PAINT SKYBLUE (-8575 3000);
FORCEPROP 1 LAST PACK_TYPE 0402
J 2
(-8575 2950);
DISPLAY 0.489362 (-8575 2950);
PAINT SKYBLUE (-8575 2950);
FORCEPROP 1 LAST VOLTAGE 25V
J 2
(-8575 3150);
DISPLAY 0.489362 (-8575 3150);
PAINT SKYBLUE (-8575 3150);
FORCEPROP 0 LAST BOM_COST MEM
J 2
(-8580 3295);
DISPLAY 0.595745 (-8580 3295);
PAINT MONO (-8580 3295);
DISPLAY INVISIBLE (-8580 3295);
FORCEPROP 2 LAST CDS_LIB pure_quanta
J 0
(-8525 3150);
DISPLAY INVISIBLE (-8525 3150);
FORCEPROP 1 LAST PATH I185
J 2
(-8575 3300);
DISPLAY 0.978723 (-8575 3300);
PAINT WHITE (-8575 3300);
DISPLAY INVISIBLE (-8575 3300);
FORCEPROP 0 LAST ROOM MEM_CH_A_CPU0_DIMM1
J 2
(-8580 3295);
DISPLAY 0.595745 (-8580 3295);
PAINT RED (-8580 3295);
DISPLAY INVISIBLE (-8580 3295);
FORCEADD GND..1
(-8525 2925);
FORCEPROP 3 LASTPIN (-8525 2975) SIG_NAME GND\g
J 0
(-8515 2985);
DISPLAY 0.659574 (-8515 2985);
PAINT MONO (-8515 2985);
DISPLAY INVISIBLE (-8515 2985);
FORCEPROP 2 LAST BOM_COST MEM
J 0
(-8500 3050);
DISPLAY 0.659574 (-8500 3050);
DISPLAY INVISIBLE (-8500 3050);
FORCEPROP 1 LAST SIZE 1B
J 0
(-8450 2875);
DISPLAY 0.723404 (-8450 2875);
PAINT GREEN (-8450 2875);
DISPLAY INVISIBLE (-8450 2875);
FORCEPROP 2 LAST CDS_LIB mstr_symbols
J 0
(-8525 2925);
DISPLAY 0.808511 (-8525 2925);
DISPLAY INVISIBLE (-8525 2925);
FORCEPROP 1 LAST BODY_TYPE PLUMBING
J 0
(-8570 2882);
DISPLAY 0.276596 (-8570 2882);
PAINT GREEN (-8570 2882);
DISPLAY INVISIBLE (-8570 2882);
FORCEPROP 1 LAST PATH I186
J 0
(-8450 2925);
DISPLAY 0.872340 (-8450 2925);
PAINT AQUA (-8450 2925);
DISPLAY INVISIBLE (-8450 2925);
FORCEPROP 1 LAST VOLTAGE 0
J 0
(-8545 3020);
DISPLAY 0.829787 (-8545 3020);
PAINT SKYBLUE (-8545 3020);
DISPLAY INVISIBLE (-8545 3020);
FORCEPROP 2 LAST ROOM MEM_EFGH_DECOUPLING_CAPS
J 0
(-8500 3000);
DISPLAY 0.659574 (-8500 3000);
PAINT RED (-8500 3000);
DISPLAY INVISIBLE (-8500 3000);
FORCEPROP 1 LAST HDL_POWER GND
J 0
(-8525 3075);
DISPLAY 0.723404 (-8525 3075);
PAINT GREEN (-8525 3075);
DISPLAY INVISIBLE (-8525 3075);
FORCEADD OFFPAGE..6
(-8925 2075);
FORCEPROP 2 LAST $XR5 81 
J 0
(-9295 2111);
DISPLAY 0.638298 (-9295 2111);
PAINT MONO (-9295 2111);
FORCEPROP 2 LAST $XR4 108 
J 0
(-9205 2111);
DISPLAY 0.638298 (-9205 2111);
PAINT MONO (-9205 2111);
FORCEPROP 2 LAST $XR3 107 
J 0
(-9325 2039);
DISPLAY 0.638298 (-9325 2039);
PAINT MONO (-9325 2039);
FORCEPROP 2 LAST $XR2 105 
J 0
(-9205 2039);
DISPLAY 0.638298 (-9205 2039);
PAINT MONO (-9205 2039);
FORCEPROP 2 LAST $XR1 104 
J 0
(-9325 2075);
DISPLAY 0.638298 (-9325 2075);
PAINT MONO (-9325 2075);
FORCEPROP 2 LAST $XR0 103 
J 0
(-9205 2075);
DISPLAY 0.638298 (-9205 2075);
PAINT MONO (-9205 2075);
FORCEPROP 2 LAST PATH I187
J 0
(-8875 2150);
DISPLAY 1.021277 (-8875 2150);
DISPLAY INVISIBLE (-8875 2150);
FORCEPROP 1 LAST COMMENT_BODY TRUE
J 0
(-8825 2000);
DISPLAY 0.872340 (-8825 2000);
PAINT GREEN (-8825 2000);
DISPLAY INVISIBLE (-8825 2000);
FORCEPROP 1 LAST OFFPAGE TRUE
J 0
(-8600 1950);
DISPLAY 0.872340 (-8600 1950);
PAINT GREEN (-8600 1950);
DISPLAY INVISIBLE (-8600 1950);
FORCEPROP 2 LAST CDS_LIB mstr_standard
J 0
(-8925 2075);
DISPLAY INVISIBLE (-8925 2075);
FORCEADD Q_RES..1
R 2
(-8375 2075);
FORCEPROP 1 LAST LOCATION R312
J 2
(-8325 2125);
DISPLAY 0.489362 (-8325 2125);
PAINT SKYBLUE (-8325 2125);
FORCEPROP 0 LAST $SEC 1
J 0
(-8325 2175);
DISPLAY 0.680851 (-8325 2175);
PAINT MONO (-8325 2175);
DISPLAY INVISIBLE (-8325 2175);
FORCEPROP 0 LAST CDS_SEC 1
J 0
(-8325 2175);
DISPLAY 1.021277 (-8325 2175);
DISPLAY INVISIBLE (-8325 2175);
FORCEPROP 1 LASTPIN (-8275 2075) $PN 1
J 2
(-8287 2087);
DISPLAY 0.489362 (-8287 2087);
PAINT MONO (-8287 2087);
FORCEPROP 1 LASTPIN (-8475 2075) $PN 2
J 2
(-8437 2087);
DISPLAY 0.489362 (-8437 2087);
PAINT MONO (-8437 2087);
FORCEPROP 1 LAST VALUE 0
J 0
(-8375 2025);
DISPLAY 0.489362 (-8375 2025);
PAINT SKYBLUE (-8375 2025);
FORCEPROP 2 LAST BOM_COST MEM
J 0
(-8400 2225);
DISPLAY 0.744681 (-8400 2225);
PAINT WHITE (-8400 2225);
DISPLAY INVISIBLE (-8400 2225);
FORCEPROP 2 LAST CDS_LIB pure_quanta
J 0
(-8375 2075);
DISPLAY INVISIBLE (-8375 2075);
FORCEPROP 1 LAST PATH I188
J 2
(-8325 2225);
DISPLAY 0.978723 (-8325 2225);
PAINT WHITE (-8325 2225);
DISPLAY INVISIBLE (-8325 2225);
FORCEPROP 1 LAST WATTAGE 1/16W
J 0
(-8300 2000);
DISPLAY 0.489362 (-8300 2000);
PAINT SKYBLUE (-8300 2000);
DISPLAY INVISIBLE (-8300 2000);
FORCEPROP 1 LAST MATERIAL CHIP
J 0
(-8550 2050);
DISPLAY 0.489362 (-8550 2050);
PAINT SKYBLUE (-8550 2050);
DISPLAY INVISIBLE (-8550 2050);
FORCEPROP 1 LAST TOLERANCE 5%
J 2
(-8250 2050);
DISPLAY 0.489362 (-8250 2050);
PAINT SKYBLUE (-8250 2050);
DISPLAY INVISIBLE (-8250 2050);
FORCEPROP 1 LAST PART_NUMBER CS00002JB38
J 0
(-8475 2125);
DISPLAY 0.489362 (-8475 2125);
PAINT SKYBLUE (-8475 2125);
DISPLAY INVISIBLE (-8475 2125);
FORCEPROP 1 LAST PACK_TYPE 0402LF
J 0
(-8550 2000);
DISPLAY 0.489362 (-8550 2000);
PAINT SKYBLUE (-8550 2000);
DISPLAY INVISIBLE (-8550 2000);
FORCEPROP 2 LAST ROOM RST_CPU0_PLD_TO_DIMM
J 0
(-8400 2175);
DISPLAY 0.744681 (-8400 2175);
PAINT RED (-8400 2175);
DISPLAY INVISIBLE (-8400 2175);
FORCEADD VCC_CORE..1
(-8250 2400);
FORCEPROP 3 LASTPIN (-8250 2350) SIG_NAME P3V3_STBY\g
J 0
(-8240 2360);
DISPLAY 0.659574 (-8240 2360);
PAINT MONO (-8240 2360);
DISPLAY INVISIBLE (-8240 2360);
FORCEPROP 1 LAST HDL_POWER P3V3_STBY
J 1
(-8250 2450);
DISPLAY 0.489362 (-8250 2450);
PAINT GREEN (-8250 2450);
FORCEPROP 2 LAST CDS_LIB mstr_symbols
J 0
(-8250 2400);
DISPLAY INVISIBLE (-8250 2400);
FORCEPROP 1 LAST PATH I189
J 0
(-8200 2425);
DISPLAY 0.872340 (-8200 2425);
PAINT AQUA (-8200 2425);
DISPLAY INVISIBLE (-8200 2425);
FORCEPROP 0 LAST VOLTAGE 3.3
J 0
(-8525 2550);
DISPLAY 1.021277 (-8525 2550);
PAINT SKYBLUE (-8525 2550);
DISPLAY INVISIBLE (-8525 2550);
FORCEPROP 2 LAST ROOM PVCCINFAON_CPU0_CTRL
J 0
(-8250 2500);
DISPLAY 0.808511 (-8250 2500);
PAINT RED (-8250 2500);
DISPLAY INVISIBLE (-8250 2500);
FORCEADD OFFPAGE..1
(-8150 4475);
FORCEPROP 2 LAST $XR0 46 
J 0
(-8401 4475);
DISPLAY 0.638298 (-8401 4475);
PAINT MONO (-8401 4475);
FORCEPROP 2 LAST PATH I19
J 0
(-8400 4525);
DISPLAY 1.021277 (-8400 4525);
DISPLAY INVISIBLE (-8400 4525);
FORCEPROP 1 LAST COMMENT_BODY TRUE
J 0
(-8025 4375);
DISPLAY 0.872340 (-8025 4375);
PAINT GREEN (-8025 4375);
DISPLAY INVISIBLE (-8025 4375);
FORCEPROP 1 LAST OFFPAGE TRUE
J 0
(-7825 4350);
DISPLAY 0.872340 (-7825 4350);
PAINT GREEN (-7825 4350);
DISPLAY INVISIBLE (-7825 4350);
FORCEPROP 2 LAST CDS_LIB mstr_standard
J 0
(-8150 4475);
DISPLAY 0.808511 (-8150 4475);
DISPLAY INVISIBLE (-8150 4475);
FORCEADD Q_RES..2
(-8250 2225);
FORCEPROP 1 LAST LOCATION R113
J 0
(-8205 2350);
DISPLAY 0.489362 (-8205 2350);
PAINT SKYBLUE (-8205 2350);
FORCEPROP 0 LAST $SEC 1
J 0
(-8200 2400);
DISPLAY 0.680851 (-8200 2400);
PAINT MONO (-8200 2400);
DISPLAY INVISIBLE (-8200 2400);
FORCEPROP 0 LAST CDS_SEC 1
J 0
(-8200 2400);
DISPLAY 1.021277 (-8200 2400);
DISPLAY INVISIBLE (-8200 2400);
FORCEPROP 1 LASTPIN (-8250 2325) $PN 1
J 0
(-8245 2287);
DISPLAY 0.489362 (-8245 2287);
PAINT MONO (-8245 2287);
FORCEPROP 1 LASTPIN (-8250 2125) $PN 2
J 0
(-8245 2135);
DISPLAY 0.489362 (-8245 2135);
PAINT MONO (-8245 2135);
FORCEPROP 1 LAST VALUE 1K
J 0
(-8205 2300);
DISPLAY 0.489362 (-8205 2300);
PAINT SKYBLUE (-8205 2300);
FORCEPROP 1 LAST TOLERANCE 5%
J 0
(-8200 2275);
DISPLAY 0.489362 (-8200 2275);
PAINT SKYBLUE (-8200 2275);
FORCEPROP 1 LAST MATERIAL EMPTY
J 0
(-8200 2225);
DISPLAY 0.489362 (-8200 2225);
PAINT RED (-8200 2225);
FORCEPROP 1 LAST PACK_TYPE 0402LF
J 0
(-8200 2175);
DISPLAY 0.489362 (-8200 2175);
PAINT SKYBLUE (-8200 2175);
FORCEPROP 1 LAST WATTAGE 1/16W
J 0
(-8200 2250);
DISPLAY 0.489362 (-8200 2250);
PAINT SKYBLUE (-8200 2250);
FORCEPROP 2 LAST BOM_COST MEM
J 0
(-8200 2400);
DISPLAY 0.808511 (-8200 2400);
DISPLAY INVISIBLE (-8200 2400);
FORCEPROP 2 LAST CDS_LIB pure_quanta
J 0
(-8250 2225);
DISPLAY INVISIBLE (-8250 2225);
FORCEPROP 1 LAST PATH I190
J 0
(-8200 2400);
DISPLAY 0.978723 (-8200 2400);
PAINT WHITE (-8200 2400);
DISPLAY INVISIBLE (-8200 2400);
FORCEPROP 1 LAST PART_NUMBER TMP_QCS21002JB34
J 0
(-8200 2200);
DISPLAY 0.489362 (-8200 2200);
PAINT SKYBLUE (-8200 2200);
DISPLAY INVISIBLE (-8200 2200);
FORCEPROP 2 LAST ROOM MEM_CH_A_CPU0_DIMM1
J 0
(-8200 2450);
DISPLAY 0.808511 (-8200 2450);
PAINT RED (-8200 2450);
DISPLAY INVISIBLE (-8200 2450);
FORCEADD OFFPAGE..2
(-2350 4700);
FORCEPROP 2 LAST $XR0 46 
J 0
(-2161 4700);
DISPLAY 0.638298 (-2161 4700);
PAINT MONO (-2161 4700);
FORCEPROP 1 LAST COMMENT_BODY TRUE
J 0
(-2395 4605);
DISPLAY 0.872340 (-2395 4605);
PAINT GREEN (-2395 4605);
DISPLAY INVISIBLE (-2395 4605);
FORCEPROP 1 LAST OFFPAGE TRUE
J 0
(-2025 4575);
DISPLAY 0.723404 (-2025 4575);
PAINT GREEN (-2025 4575);
DISPLAY INVISIBLE (-2025 4575);
FORCEPROP 2 LAST CDS_LIB mstr_standard
J 0
(-2350 4700);
DISPLAY 0.723404 (-2350 4700);
PAINT MONO (-2350 4700);
DISPLAY INVISIBLE (-2350 4700);
FORCEPROP 2 LAST PATH I192
J 0
(-2150 4750);
DISPLAY 0.680851 (-2150 4750);
DISPLAY INVISIBLE (-2150 4750);
FORCEADD OFFPAGE..2
(-2350 4650);
FORCEPROP 2 LAST $XR0 46 
J 0
(-2161 4650);
DISPLAY 0.638298 (-2161 4650);
PAINT MONO (-2161 4650);
FORCEPROP 1 LAST COMMENT_BODY TRUE
J 0
(-2395 4555);
DISPLAY 0.872340 (-2395 4555);
PAINT GREEN (-2395 4555);
DISPLAY INVISIBLE (-2395 4555);
FORCEPROP 1 LAST OFFPAGE TRUE
J 0
(-2025 4525);
DISPLAY 0.723404 (-2025 4525);
PAINT GREEN (-2025 4525);
DISPLAY INVISIBLE (-2025 4525);
FORCEPROP 2 LAST CDS_LIB mstr_standard
J 0
(-2350 4650);
DISPLAY 0.723404 (-2350 4650);
PAINT MONO (-2350 4650);
DISPLAY INVISIBLE (-2350 4650);
FORCEPROP 2 LAST PATH I193
J 0
(-2150 4700);
DISPLAY 0.680851 (-2150 4700);
DISPLAY INVISIBLE (-2150 4700);
FORCEADD OFFPAGE..2
(-2350 3650);
FORCEPROP 2 LAST $XR0 46 
J 0
(-2161 3650);
DISPLAY 0.638298 (-2161 3650);
PAINT MONO (-2161 3650);
FORCEPROP 1 LAST COMMENT_BODY TRUE
J 0
(-2395 3555);
DISPLAY 0.872340 (-2395 3555);
PAINT GREEN (-2395 3555);
DISPLAY INVISIBLE (-2395 3555);
FORCEPROP 1 LAST OFFPAGE TRUE
J 0
(-2025 3525);
DISPLAY 0.723404 (-2025 3525);
PAINT GREEN (-2025 3525);
DISPLAY INVISIBLE (-2025 3525);
FORCEPROP 2 LAST CDS_LIB mstr_standard
J 0
(-2350 3650);
DISPLAY 0.723404 (-2350 3650);
PAINT MONO (-2350 3650);
DISPLAY INVISIBLE (-2350 3650);
FORCEPROP 2 LAST PATH I194
J 0
(-2150 3700);
DISPLAY 0.680851 (-2150 3700);
DISPLAY INVISIBLE (-2150 3700);
FORCEADD OFFPAGE..2
(-2350 3600);
FORCEPROP 2 LAST $XR0 46 
J 0
(-2161 3600);
DISPLAY 0.638298 (-2161 3600);
PAINT MONO (-2161 3600);
FORCEPROP 1 LAST COMMENT_BODY TRUE
J 0
(-2395 3505);
DISPLAY 0.872340 (-2395 3505);
PAINT GREEN (-2395 3505);
DISPLAY INVISIBLE (-2395 3505);
FORCEPROP 1 LAST OFFPAGE TRUE
J 0
(-2025 3475);
DISPLAY 0.723404 (-2025 3475);
PAINT GREEN (-2025 3475);
DISPLAY INVISIBLE (-2025 3475);
FORCEPROP 2 LAST CDS_LIB mstr_standard
J 0
(-2350 3600);
DISPLAY 0.723404 (-2350 3600);
PAINT MONO (-2350 3600);
DISPLAY INVISIBLE (-2350 3600);
FORCEPROP 2 LAST PATH I195
J 0
(-2150 3650);
DISPLAY 0.680851 (-2150 3650);
DISPLAY INVISIBLE (-2150 3650);
FORCEADD TAP..1
(-3150 4600);
FORCEPROP 3 LASTPIN (-3200 4600) SIG_NAME M_J_CPU1_SA_DQS_DN<9>
J 0
(-3190 4610);
DISPLAY 0.659574 (-3190 4610);
PAINT MONO (-3190 4610);
DISPLAY INVISIBLE (-3190 4610);
FORCEPROP 1 LASTPIN (-3200 4600) BN 9
J 0
(-3212 4608);
DISPLAY 0.489362 (-3212 4608);
PAINT GREEN (-3212 4608);
FORCEPROP 2 LAST CDS_LIB mstr_standard
J 0
(-3150 4600);
DISPLAY 0.723404 (-3150 4600);
PAINT MONO (-3150 4600);
DISPLAY INVISIBLE (-3150 4600);
FORCEPROP 1 LAST BODY_TYPE PLUMBING
J 0
(-3150 4650);
DISPLAY 0.872340 (-3150 4650);
PAINT GREEN (-3150 4650);
DISPLAY INVISIBLE (-3150 4650);
FORCEPROP 1 LAST HDL_TAP TRUE
J 0
(-2825 4475);
DISPLAY 0.872340 (-2825 4475);
DISPLAY INVISIBLE (-2825 4475);
FORCEPROP 1 LAST PATH I196
J 0
(-3152 4600);
DISPLAY 0.872340 (-3152 4600);
PAINT GREEN (-3152 4600);
DISPLAY INVISIBLE (-3152 4600);
FORCEADD TAP..1
(-3350 4650);
FORCEPROP 3 LASTPIN (-3400 4650) SIG_NAME M_J_CPU1_SA_DQS_DP<9>
J 0
(-3390 4660);
DISPLAY 0.659574 (-3390 4660);
PAINT MONO (-3390 4660);
DISPLAY INVISIBLE (-3390 4660);
FORCEPROP 1 LASTPIN (-3400 4650) BN 9
J 0
(-3412 4658);
DISPLAY 0.489362 (-3412 4658);
PAINT GREEN (-3412 4658);
FORCEPROP 2 LAST CDS_LIB mstr_standard
J 0
(-3350 4650);
DISPLAY 0.723404 (-3350 4650);
PAINT MONO (-3350 4650);
DISPLAY INVISIBLE (-3350 4650);
FORCEPROP 1 LAST BODY_TYPE PLUMBING
J 0
(-3350 4700);
DISPLAY 0.872340 (-3350 4700);
PAINT GREEN (-3350 4700);
DISPLAY INVISIBLE (-3350 4700);
FORCEPROP 1 LAST HDL_TAP TRUE
J 0
(-3025 4525);
DISPLAY 0.872340 (-3025 4525);
DISPLAY INVISIBLE (-3025 4525);
FORCEPROP 1 LAST PATH I197
J 0
(-3352 4650);
DISPLAY 0.872340 (-3352 4650);
PAINT GREEN (-3352 4650);
DISPLAY INVISIBLE (-3352 4650);
FORCEADD TAP..1
(-3350 4550);
FORCEPROP 3 LASTPIN (-3400 4550) SIG_NAME M_J_CPU1_SA_DQS_DP<8>
J 0
(-3390 4560);
DISPLAY 0.659574 (-3390 4560);
PAINT MONO (-3390 4560);
DISPLAY INVISIBLE (-3390 4560);
FORCEPROP 1 LASTPIN (-3400 4550) BN 8
J 0
(-3412 4558);
DISPLAY 0.489362 (-3412 4558);
PAINT GREEN (-3412 4558);
FORCEPROP 2 LAST CDS_LIB mstr_standard
J 0
(-3350 4550);
DISPLAY 0.723404 (-3350 4550);
PAINT MONO (-3350 4550);
DISPLAY INVISIBLE (-3350 4550);
FORCEPROP 1 LAST BODY_TYPE PLUMBING
J 0
(-3350 4600);
DISPLAY 0.872340 (-3350 4600);
PAINT GREEN (-3350 4600);
DISPLAY INVISIBLE (-3350 4600);
FORCEPROP 1 LAST HDL_TAP TRUE
J 0
(-3025 4425);
DISPLAY 0.872340 (-3025 4425);
DISPLAY INVISIBLE (-3025 4425);
FORCEPROP 1 LAST PATH I198
J 0
(-3352 4550);
DISPLAY 0.872340 (-3352 4550);
PAINT GREEN (-3352 4550);
DISPLAY INVISIBLE (-3352 4550);
FORCEADD TAP..1
(-3150 4500);
FORCEPROP 3 LASTPIN (-3200 4500) SIG_NAME M_J_CPU1_SA_DQS_DN<8>
J 0
(-3190 4510);
DISPLAY 0.659574 (-3190 4510);
PAINT MONO (-3190 4510);
DISPLAY INVISIBLE (-3190 4510);
FORCEPROP 1 LASTPIN (-3200 4500) BN 8
J 0
(-3212 4508);
DISPLAY 0.489362 (-3212 4508);
PAINT GREEN (-3212 4508);
FORCEPROP 2 LAST CDS_LIB mstr_standard
J 0
(-3150 4500);
DISPLAY 0.723404 (-3150 4500);
PAINT MONO (-3150 4500);
DISPLAY INVISIBLE (-3150 4500);
FORCEPROP 1 LAST BODY_TYPE PLUMBING
J 0
(-3150 4550);
DISPLAY 0.872340 (-3150 4550);
PAINT GREEN (-3150 4550);
DISPLAY INVISIBLE (-3150 4550);
FORCEPROP 1 LAST HDL_TAP TRUE
J 0
(-2825 4375);
DISPLAY 0.872340 (-2825 4375);
DISPLAY INVISIBLE (-2825 4375);
FORCEPROP 1 LAST PATH I199
J 0
(-3152 4500);
DISPLAY 0.872340 (-3152 4500);
PAINT GREEN (-3152 4500);
DISPLAY INVISIBLE (-3152 4500);
FORCEADD OFFPAGE..1
(-8150 4975);
FORCEPROP 2 LAST $XR0 46 
J 0
(-8401 4975);
DISPLAY 0.638298 (-8401 4975);
PAINT MONO (-8401 4975);
FORCEPROP 2 LAST PATH I20
J 0
(-8400 5025);
DISPLAY 1.021277 (-8400 5025);
DISPLAY INVISIBLE (-8400 5025);
FORCEPROP 1 LAST COMMENT_BODY TRUE
J 0
(-8025 4875);
DISPLAY 0.872340 (-8025 4875);
PAINT GREEN (-8025 4875);
DISPLAY INVISIBLE (-8025 4875);
FORCEPROP 1 LAST OFFPAGE TRUE
J 0
(-7825 4850);
DISPLAY 0.872340 (-7825 4850);
PAINT GREEN (-7825 4850);
DISPLAY INVISIBLE (-7825 4850);
FORCEPROP 2 LAST CDS_LIB mstr_standard
J 0
(-8150 4975);
DISPLAY 0.723404 (-8150 4975);
PAINT MONO (-8150 4975);
DISPLAY INVISIBLE (-8150 4975);
FORCEADD TAP..1
(-3150 4300);
FORCEPROP 3 LASTPIN (-3200 4300) SIG_NAME M_J_CPU1_SA_DQS_DN<6>
J 0
(-3190 4310);
DISPLAY 0.659574 (-3190 4310);
PAINT MONO (-3190 4310);
DISPLAY INVISIBLE (-3190 4310);
FORCEPROP 1 LASTPIN (-3200 4300) BN 6
J 0
(-3212 4308);
DISPLAY 0.489362 (-3212 4308);
PAINT GREEN (-3212 4308);
FORCEPROP 2 LAST CDS_LIB mstr_standard
J 0
(-3150 4300);
DISPLAY 0.723404 (-3150 4300);
PAINT MONO (-3150 4300);
DISPLAY INVISIBLE (-3150 4300);
FORCEPROP 1 LAST BODY_TYPE PLUMBING
J 0
(-3150 4350);
DISPLAY 0.872340 (-3150 4350);
PAINT GREEN (-3150 4350);
DISPLAY INVISIBLE (-3150 4350);
FORCEPROP 1 LAST HDL_TAP TRUE
J 0
(-2825 4175);
DISPLAY 0.872340 (-2825 4175);
DISPLAY INVISIBLE (-2825 4175);
FORCEPROP 1 LAST PATH I200
J 0
(-3152 4300);
DISPLAY 0.872340 (-3152 4300);
PAINT GREEN (-3152 4300);
DISPLAY INVISIBLE (-3152 4300);
FORCEADD TAP..1
(-3150 4400);
FORCEPROP 3 LASTPIN (-3200 4400) SIG_NAME M_J_CPU1_SA_DQS_DN<7>
J 0
(-3190 4410);
DISPLAY 0.659574 (-3190 4410);
PAINT MONO (-3190 4410);
DISPLAY INVISIBLE (-3190 4410);
FORCEPROP 1 LASTPIN (-3200 4400) BN 7
J 0
(-3212 4408);
DISPLAY 0.489362 (-3212 4408);
PAINT GREEN (-3212 4408);
FORCEPROP 2 LAST CDS_LIB mstr_standard
J 0
(-3150 4400);
DISPLAY 0.723404 (-3150 4400);
PAINT MONO (-3150 4400);
DISPLAY INVISIBLE (-3150 4400);
FORCEPROP 1 LAST BODY_TYPE PLUMBING
J 0
(-3150 4450);
DISPLAY 0.872340 (-3150 4450);
PAINT GREEN (-3150 4450);
DISPLAY INVISIBLE (-3150 4450);
FORCEPROP 1 LAST HDL_TAP TRUE
J 0
(-2825 4275);
DISPLAY 0.872340 (-2825 4275);
DISPLAY INVISIBLE (-2825 4275);
FORCEPROP 1 LAST PATH I201
J 0
(-3152 4400);
DISPLAY 0.872340 (-3152 4400);
PAINT GREEN (-3152 4400);
DISPLAY INVISIBLE (-3152 4400);
FORCEADD TAP..1
(-3150 4200);
FORCEPROP 3 LASTPIN (-3200 4200) SIG_NAME M_J_CPU1_SA_DQS_DN<5>
J 0
(-3190 4210);
DISPLAY 0.659574 (-3190 4210);
PAINT MONO (-3190 4210);
DISPLAY INVISIBLE (-3190 4210);
FORCEPROP 1 LASTPIN (-3200 4200) BN 5
J 0
(-3212 4208);
DISPLAY 0.489362 (-3212 4208);
PAINT GREEN (-3212 4208);
FORCEPROP 2 LAST CDS_LIB mstr_standard
J 0
(-3150 4200);
DISPLAY 0.723404 (-3150 4200);
PAINT MONO (-3150 4200);
DISPLAY INVISIBLE (-3150 4200);
FORCEPROP 1 LAST BODY_TYPE PLUMBING
J 0
(-3150 4250);
DISPLAY 0.872340 (-3150 4250);
PAINT GREEN (-3150 4250);
DISPLAY INVISIBLE (-3150 4250);
FORCEPROP 1 LAST HDL_TAP TRUE
J 0
(-2825 4075);
DISPLAY 0.872340 (-2825 4075);
DISPLAY INVISIBLE (-2825 4075);
FORCEPROP 1 LAST PATH I202
J 0
(-3152 4200);
DISPLAY 0.872340 (-3152 4200);
PAINT GREEN (-3152 4200);
DISPLAY INVISIBLE (-3152 4200);
FORCEADD TAP..1
(-3150 4100);
FORCEPROP 3 LASTPIN (-3200 4100) SIG_NAME M_J_CPU1_SA_DQS_DN<4>
J 0
(-3190 4110);
DISPLAY 0.659574 (-3190 4110);
PAINT MONO (-3190 4110);
DISPLAY INVISIBLE (-3190 4110);
FORCEPROP 1 LASTPIN (-3200 4100) BN 4
J 0
(-3212 4108);
DISPLAY 0.489362 (-3212 4108);
PAINT GREEN (-3212 4108);
FORCEPROP 2 LAST CDS_LIB mstr_standard
J 0
(-3150 4100);
DISPLAY 0.723404 (-3150 4100);
PAINT MONO (-3150 4100);
DISPLAY INVISIBLE (-3150 4100);
FORCEPROP 1 LAST BODY_TYPE PLUMBING
J 0
(-3150 4150);
DISPLAY 0.872340 (-3150 4150);
PAINT GREEN (-3150 4150);
DISPLAY INVISIBLE (-3150 4150);
FORCEPROP 1 LAST HDL_TAP TRUE
J 0
(-2825 3975);
DISPLAY 0.872340 (-2825 3975);
DISPLAY INVISIBLE (-2825 3975);
FORCEPROP 1 LAST PATH I203
J 0
(-3152 4100);
DISPLAY 0.872340 (-3152 4100);
PAINT GREEN (-3152 4100);
DISPLAY INVISIBLE (-3152 4100);
FORCEADD TAP..1
(-3150 4000);
FORCEPROP 3 LASTPIN (-3200 4000) SIG_NAME M_J_CPU1_SA_DQS_DN<3>
J 0
(-3190 4010);
DISPLAY 0.659574 (-3190 4010);
PAINT MONO (-3190 4010);
DISPLAY INVISIBLE (-3190 4010);
FORCEPROP 1 LASTPIN (-3200 4000) BN 3
J 0
(-3212 4008);
DISPLAY 0.489362 (-3212 4008);
PAINT GREEN (-3212 4008);
FORCEPROP 2 LAST CDS_LIB mstr_standard
J 0
(-3150 4000);
DISPLAY 0.723404 (-3150 4000);
PAINT MONO (-3150 4000);
DISPLAY INVISIBLE (-3150 4000);
FORCEPROP 1 LAST BODY_TYPE PLUMBING
J 0
(-3150 4050);
DISPLAY 0.872340 (-3150 4050);
PAINT GREEN (-3150 4050);
DISPLAY INVISIBLE (-3150 4050);
FORCEPROP 1 LAST HDL_TAP TRUE
J 0
(-2825 3875);
DISPLAY 0.872340 (-2825 3875);
DISPLAY INVISIBLE (-2825 3875);
FORCEPROP 1 LAST PATH I204
J 0
(-3152 4000);
DISPLAY 0.872340 (-3152 4000);
PAINT GREEN (-3152 4000);
DISPLAY INVISIBLE (-3152 4000);
FORCEADD TAP..1
(-3150 3800);
FORCEPROP 3 LASTPIN (-3200 3800) SIG_NAME M_J_CPU1_SA_DQS_DN<1>
J 0
(-3190 3810);
DISPLAY 0.659574 (-3190 3810);
PAINT MONO (-3190 3810);
DISPLAY INVISIBLE (-3190 3810);
FORCEPROP 1 LASTPIN (-3200 3800) BN 1
J 0
(-3212 3808);
DISPLAY 0.489362 (-3212 3808);
PAINT GREEN (-3212 3808);
FORCEPROP 2 LAST CDS_LIB mstr_standard
J 0
(-3150 3800);
DISPLAY 0.723404 (-3150 3800);
PAINT MONO (-3150 3800);
DISPLAY INVISIBLE (-3150 3800);
FORCEPROP 1 LAST BODY_TYPE PLUMBING
J 0
(-3150 3850);
DISPLAY 0.872340 (-3150 3850);
PAINT GREEN (-3150 3850);
DISPLAY INVISIBLE (-3150 3850);
FORCEPROP 1 LAST HDL_TAP TRUE
J 0
(-2825 3675);
DISPLAY 0.872340 (-2825 3675);
DISPLAY INVISIBLE (-2825 3675);
FORCEPROP 1 LAST PATH I205
J 0
(-3152 3800);
DISPLAY 0.872340 (-3152 3800);
PAINT GREEN (-3152 3800);
DISPLAY INVISIBLE (-3152 3800);
FORCEADD TAP..1
(-3150 3900);
FORCEPROP 3 LASTPIN (-3200 3900) SIG_NAME M_J_CPU1_SA_DQS_DN<2>
J 0
(-3190 3910);
DISPLAY 0.659574 (-3190 3910);
PAINT MONO (-3190 3910);
DISPLAY INVISIBLE (-3190 3910);
FORCEPROP 1 LASTPIN (-3200 3900) BN 2
J 0
(-3212 3908);
DISPLAY 0.489362 (-3212 3908);
PAINT GREEN (-3212 3908);
FORCEPROP 2 LAST CDS_LIB mstr_standard
J 0
(-3150 3900);
DISPLAY 0.723404 (-3150 3900);
PAINT MONO (-3150 3900);
DISPLAY INVISIBLE (-3150 3900);
FORCEPROP 1 LAST BODY_TYPE PLUMBING
J 0
(-3150 3950);
DISPLAY 0.872340 (-3150 3950);
PAINT GREEN (-3150 3950);
DISPLAY INVISIBLE (-3150 3950);
FORCEPROP 1 LAST HDL_TAP TRUE
J 0
(-2825 3775);
DISPLAY 0.872340 (-2825 3775);
DISPLAY INVISIBLE (-2825 3775);
FORCEPROP 1 LAST PATH I206
J 0
(-3152 3900);
DISPLAY 0.872340 (-3152 3900);
PAINT GREEN (-3152 3900);
DISPLAY INVISIBLE (-3152 3900);
FORCEADD TAP..1
(-3150 3700);
FORCEPROP 3 LASTPIN (-3200 3700) SIG_NAME M_J_CPU1_SA_DQS_DN<0>
J 0
(-3190 3710);
DISPLAY 0.659574 (-3190 3710);
PAINT MONO (-3190 3710);
DISPLAY INVISIBLE (-3190 3710);
FORCEPROP 1 LASTPIN (-3200 3700) BN 0
J 0
(-3212 3708);
DISPLAY 0.489362 (-3212 3708);
PAINT GREEN (-3212 3708);
FORCEPROP 2 LAST CDS_LIB mstr_standard
J 0
(-3150 3700);
DISPLAY 0.723404 (-3150 3700);
PAINT MONO (-3150 3700);
DISPLAY INVISIBLE (-3150 3700);
FORCEPROP 1 LAST BODY_TYPE PLUMBING
J 0
(-3150 3750);
DISPLAY 0.872340 (-3150 3750);
PAINT GREEN (-3150 3750);
DISPLAY INVISIBLE (-3150 3750);
FORCEPROP 1 LAST HDL_TAP TRUE
J 0
(-2825 3575);
DISPLAY 0.872340 (-2825 3575);
DISPLAY INVISIBLE (-2825 3575);
FORCEPROP 1 LAST PATH I207
J 0
(-3152 3700);
DISPLAY 0.872340 (-3152 3700);
PAINT GREEN (-3152 3700);
DISPLAY INVISIBLE (-3152 3700);
FORCEADD TAP..1
(-3150 3550);
FORCEPROP 3 LASTPIN (-3200 3550) SIG_NAME M_J_CPU1_SB_DQS_DN<9>
J 0
(-3190 3560);
DISPLAY 0.659574 (-3190 3560);
PAINT MONO (-3190 3560);
DISPLAY INVISIBLE (-3190 3560);
FORCEPROP 1 LASTPIN (-3200 3550) BN 9
J 0
(-3212 3558);
DISPLAY 0.489362 (-3212 3558);
PAINT GREEN (-3212 3558);
FORCEPROP 2 LAST CDS_LIB mstr_standard
J 0
(-3150 3550);
DISPLAY 0.723404 (-3150 3550);
PAINT MONO (-3150 3550);
DISPLAY INVISIBLE (-3150 3550);
FORCEPROP 1 LAST BODY_TYPE PLUMBING
J 0
(-3150 3600);
DISPLAY 0.872340 (-3150 3600);
PAINT GREEN (-3150 3600);
DISPLAY INVISIBLE (-3150 3600);
FORCEPROP 1 LAST HDL_TAP TRUE
J 0
(-2825 3425);
DISPLAY 0.872340 (-2825 3425);
DISPLAY INVISIBLE (-2825 3425);
FORCEPROP 1 LAST PATH I208
J 0
(-3152 3550);
DISPLAY 0.872340 (-3152 3550);
PAINT GREEN (-3152 3550);
DISPLAY INVISIBLE (-3152 3550);
FORCEADD TAP..1
(-3350 4450);
FORCEPROP 3 LASTPIN (-3400 4450) SIG_NAME M_J_CPU1_SA_DQS_DP<7>
J 0
(-3390 4460);
DISPLAY 0.659574 (-3390 4460);
PAINT MONO (-3390 4460);
DISPLAY INVISIBLE (-3390 4460);
FORCEPROP 1 LASTPIN (-3400 4450) BN 7
J 0
(-3412 4458);
DISPLAY 0.489362 (-3412 4458);
PAINT GREEN (-3412 4458);
FORCEPROP 2 LAST CDS_LIB mstr_standard
J 0
(-3350 4450);
DISPLAY 0.723404 (-3350 4450);
PAINT MONO (-3350 4450);
DISPLAY INVISIBLE (-3350 4450);
FORCEPROP 1 LAST BODY_TYPE PLUMBING
J 0
(-3350 4500);
DISPLAY 0.872340 (-3350 4500);
PAINT GREEN (-3350 4500);
DISPLAY INVISIBLE (-3350 4500);
FORCEPROP 1 LAST HDL_TAP TRUE
J 0
(-3025 4325);
DISPLAY 0.872340 (-3025 4325);
DISPLAY INVISIBLE (-3025 4325);
FORCEPROP 1 LAST PATH I209
J 0
(-3352 4450);
DISPLAY 0.872340 (-3352 4450);
PAINT GREEN (-3352 4450);
DISPLAY INVISIBLE (-3352 4450);
FORCEADD OFFPAGE..1
(-8150 5375);
FORCEPROP 2 LAST $XR0 46 
J 0
(-8401 5375);
DISPLAY 0.638298 (-8401 5375);
PAINT MONO (-8401 5375);
FORCEPROP 2 LAST PATH I21
J 0
(-8400 5425);
DISPLAY 1.021277 (-8400 5425);
DISPLAY INVISIBLE (-8400 5425);
FORCEPROP 1 LAST COMMENT_BODY TRUE
J 0
(-8025 5275);
DISPLAY 0.872340 (-8025 5275);
PAINT GREEN (-8025 5275);
DISPLAY INVISIBLE (-8025 5275);
FORCEPROP 1 LAST OFFPAGE TRUE
J 0
(-7825 5250);
DISPLAY 0.872340 (-7825 5250);
PAINT GREEN (-7825 5250);
DISPLAY INVISIBLE (-7825 5250);
FORCEPROP 2 LAST CDS_LIB mstr_standard
J 0
(-8150 5375);
DISPLAY 0.723404 (-8150 5375);
PAINT MONO (-8150 5375);
DISPLAY INVISIBLE (-8150 5375);
FORCEADD TAP..1
(-3350 4350);
FORCEPROP 3 LASTPIN (-3400 4350) SIG_NAME M_J_CPU1_SA_DQS_DP<6>
J 0
(-3390 4360);
DISPLAY 0.659574 (-3390 4360);
PAINT MONO (-3390 4360);
DISPLAY INVISIBLE (-3390 4360);
FORCEPROP 1 LASTPIN (-3400 4350) BN 6
J 0
(-3412 4358);
DISPLAY 0.489362 (-3412 4358);
PAINT GREEN (-3412 4358);
FORCEPROP 2 LAST CDS_LIB mstr_standard
J 0
(-3350 4350);
DISPLAY 0.723404 (-3350 4350);
PAINT MONO (-3350 4350);
DISPLAY INVISIBLE (-3350 4350);
FORCEPROP 1 LAST BODY_TYPE PLUMBING
J 0
(-3350 4400);
DISPLAY 0.872340 (-3350 4400);
PAINT GREEN (-3350 4400);
DISPLAY INVISIBLE (-3350 4400);
FORCEPROP 1 LAST HDL_TAP TRUE
J 0
(-3025 4225);
DISPLAY 0.872340 (-3025 4225);
DISPLAY INVISIBLE (-3025 4225);
FORCEPROP 1 LAST PATH I210
J 0
(-3352 4350);
DISPLAY 0.872340 (-3352 4350);
PAINT GREEN (-3352 4350);
DISPLAY INVISIBLE (-3352 4350);
FORCEADD TAP..1
(-3350 4250);
FORCEPROP 3 LASTPIN (-3400 4250) SIG_NAME M_J_CPU1_SA_DQS_DP<5>
J 0
(-3390 4260);
DISPLAY 0.659574 (-3390 4260);
PAINT MONO (-3390 4260);
DISPLAY INVISIBLE (-3390 4260);
FORCEPROP 1 LASTPIN (-3400 4250) BN 5
J 0
(-3412 4258);
DISPLAY 0.489362 (-3412 4258);
PAINT GREEN (-3412 4258);
FORCEPROP 2 LAST CDS_LIB mstr_standard
J 0
(-3350 4250);
DISPLAY 0.723404 (-3350 4250);
PAINT MONO (-3350 4250);
DISPLAY INVISIBLE (-3350 4250);
FORCEPROP 1 LAST BODY_TYPE PLUMBING
J 0
(-3350 4300);
DISPLAY 0.872340 (-3350 4300);
PAINT GREEN (-3350 4300);
DISPLAY INVISIBLE (-3350 4300);
FORCEPROP 1 LAST HDL_TAP TRUE
J 0
(-3025 4125);
DISPLAY 0.872340 (-3025 4125);
DISPLAY INVISIBLE (-3025 4125);
FORCEPROP 1 LAST PATH I211
J 0
(-3352 4250);
DISPLAY 0.872340 (-3352 4250);
PAINT GREEN (-3352 4250);
DISPLAY INVISIBLE (-3352 4250);
FORCEADD TAP..1
(-3350 4050);
FORCEPROP 3 LASTPIN (-3400 4050) SIG_NAME M_J_CPU1_SA_DQS_DP<3>
J 0
(-3390 4060);
DISPLAY 0.659574 (-3390 4060);
PAINT MONO (-3390 4060);
DISPLAY INVISIBLE (-3390 4060);
FORCEPROP 1 LASTPIN (-3400 4050) BN 3
J 0
(-3412 4058);
DISPLAY 0.489362 (-3412 4058);
PAINT GREEN (-3412 4058);
FORCEPROP 2 LAST CDS_LIB mstr_standard
J 0
(-3350 4050);
DISPLAY 0.723404 (-3350 4050);
PAINT MONO (-3350 4050);
DISPLAY INVISIBLE (-3350 4050);
FORCEPROP 1 LAST BODY_TYPE PLUMBING
J 0
(-3350 4100);
DISPLAY 0.872340 (-3350 4100);
PAINT GREEN (-3350 4100);
DISPLAY INVISIBLE (-3350 4100);
FORCEPROP 1 LAST HDL_TAP TRUE
J 0
(-3025 3925);
DISPLAY 0.872340 (-3025 3925);
DISPLAY INVISIBLE (-3025 3925);
FORCEPROP 1 LAST PATH I212
J 0
(-3352 4050);
DISPLAY 0.872340 (-3352 4050);
PAINT GREEN (-3352 4050);
DISPLAY INVISIBLE (-3352 4050);
FORCEADD TAP..1
(-3350 4150);
FORCEPROP 3 LASTPIN (-3400 4150) SIG_NAME M_J_CPU1_SA_DQS_DP<4>
J 0
(-3390 4160);
DISPLAY 0.659574 (-3390 4160);
PAINT MONO (-3390 4160);
DISPLAY INVISIBLE (-3390 4160);
FORCEPROP 1 LASTPIN (-3400 4150) BN 4
J 0
(-3412 4158);
DISPLAY 0.489362 (-3412 4158);
PAINT GREEN (-3412 4158);
FORCEPROP 2 LAST CDS_LIB mstr_standard
J 0
(-3350 4150);
DISPLAY 0.723404 (-3350 4150);
PAINT MONO (-3350 4150);
DISPLAY INVISIBLE (-3350 4150);
FORCEPROP 1 LAST BODY_TYPE PLUMBING
J 0
(-3350 4200);
DISPLAY 0.872340 (-3350 4200);
PAINT GREEN (-3350 4200);
DISPLAY INVISIBLE (-3350 4200);
FORCEPROP 1 LAST HDL_TAP TRUE
J 0
(-3025 4025);
DISPLAY 0.872340 (-3025 4025);
DISPLAY INVISIBLE (-3025 4025);
FORCEPROP 1 LAST PATH I213
J 0
(-3352 4150);
DISPLAY 0.872340 (-3352 4150);
PAINT GREEN (-3352 4150);
DISPLAY INVISIBLE (-3352 4150);
FORCEADD TAP..1
(-3350 3950);
FORCEPROP 3 LASTPIN (-3400 3950) SIG_NAME M_J_CPU1_SA_DQS_DP<2>
J 0
(-3390 3960);
DISPLAY 0.659574 (-3390 3960);
PAINT MONO (-3390 3960);
DISPLAY INVISIBLE (-3390 3960);
FORCEPROP 1 LASTPIN (-3400 3950) BN 2
J 0
(-3412 3958);
DISPLAY 0.489362 (-3412 3958);
PAINT GREEN (-3412 3958);
FORCEPROP 2 LAST CDS_LIB mstr_standard
J 0
(-3350 3950);
DISPLAY 0.723404 (-3350 3950);
PAINT MONO (-3350 3950);
DISPLAY INVISIBLE (-3350 3950);
FORCEPROP 1 LAST BODY_TYPE PLUMBING
J 0
(-3350 4000);
DISPLAY 0.872340 (-3350 4000);
PAINT GREEN (-3350 4000);
DISPLAY INVISIBLE (-3350 4000);
FORCEPROP 1 LAST HDL_TAP TRUE
J 0
(-3025 3825);
DISPLAY 0.872340 (-3025 3825);
DISPLAY INVISIBLE (-3025 3825);
FORCEPROP 1 LAST PATH I214
J 0
(-3352 3950);
DISPLAY 0.872340 (-3352 3950);
PAINT GREEN (-3352 3950);
DISPLAY INVISIBLE (-3352 3950);
FORCEADD TAP..1
(-3350 3850);
FORCEPROP 3 LASTPIN (-3400 3850) SIG_NAME M_J_CPU1_SA_DQS_DP<1>
J 0
(-3390 3860);
DISPLAY 0.659574 (-3390 3860);
PAINT MONO (-3390 3860);
DISPLAY INVISIBLE (-3390 3860);
FORCEPROP 1 LASTPIN (-3400 3850) BN 1
J 0
(-3412 3858);
DISPLAY 0.489362 (-3412 3858);
PAINT GREEN (-3412 3858);
FORCEPROP 2 LAST CDS_LIB mstr_standard
J 0
(-3350 3850);
DISPLAY 0.723404 (-3350 3850);
PAINT MONO (-3350 3850);
DISPLAY INVISIBLE (-3350 3850);
FORCEPROP 1 LAST BODY_TYPE PLUMBING
J 0
(-3350 3900);
DISPLAY 0.872340 (-3350 3900);
PAINT GREEN (-3350 3900);
DISPLAY INVISIBLE (-3350 3900);
FORCEPROP 1 LAST HDL_TAP TRUE
J 0
(-3025 3725);
DISPLAY 0.872340 (-3025 3725);
DISPLAY INVISIBLE (-3025 3725);
FORCEPROP 1 LAST PATH I215
J 0
(-3352 3850);
DISPLAY 0.872340 (-3352 3850);
PAINT GREEN (-3352 3850);
DISPLAY INVISIBLE (-3352 3850);
FORCEADD TAP..1
(-3350 3600);
FORCEPROP 3 LASTPIN (-3400 3600) SIG_NAME M_J_CPU1_SB_DQS_DP<9>
J 0
(-3390 3610);
DISPLAY 0.659574 (-3390 3610);
PAINT MONO (-3390 3610);
DISPLAY INVISIBLE (-3390 3610);
FORCEPROP 1 LASTPIN (-3400 3600) BN 9
J 0
(-3412 3608);
DISPLAY 0.489362 (-3412 3608);
PAINT GREEN (-3412 3608);
FORCEPROP 2 LAST CDS_LIB mstr_standard
J 0
(-3350 3600);
DISPLAY 0.723404 (-3350 3600);
PAINT MONO (-3350 3600);
DISPLAY INVISIBLE (-3350 3600);
FORCEPROP 1 LAST BODY_TYPE PLUMBING
J 0
(-3350 3650);
DISPLAY 0.872340 (-3350 3650);
PAINT GREEN (-3350 3650);
DISPLAY INVISIBLE (-3350 3650);
FORCEPROP 1 LAST HDL_TAP TRUE
J 0
(-3025 3475);
DISPLAY 0.872340 (-3025 3475);
DISPLAY INVISIBLE (-3025 3475);
FORCEPROP 1 LAST PATH I216
J 0
(-3352 3600);
DISPLAY 0.872340 (-3352 3600);
PAINT GREEN (-3352 3600);
DISPLAY INVISIBLE (-3352 3600);
FORCEADD TAP..1
(-3350 3750);
FORCEPROP 3 LASTPIN (-3400 3750) SIG_NAME M_J_CPU1_SA_DQS_DP<0>
J 0
(-3390 3760);
DISPLAY 0.659574 (-3390 3760);
PAINT MONO (-3390 3760);
DISPLAY INVISIBLE (-3390 3760);
FORCEPROP 1 LASTPIN (-3400 3750) BN 0
J 0
(-3412 3758);
DISPLAY 0.489362 (-3412 3758);
PAINT GREEN (-3412 3758);
FORCEPROP 2 LAST CDS_LIB mstr_standard
J 0
(-3350 3750);
DISPLAY 0.723404 (-3350 3750);
PAINT MONO (-3350 3750);
DISPLAY INVISIBLE (-3350 3750);
FORCEPROP 1 LAST BODY_TYPE PLUMBING
J 0
(-3350 3800);
DISPLAY 0.872340 (-3350 3800);
PAINT GREEN (-3350 3800);
DISPLAY INVISIBLE (-3350 3800);
FORCEPROP 1 LAST HDL_TAP TRUE
J 0
(-3025 3625);
DISPLAY 0.872340 (-3025 3625);
DISPLAY INVISIBLE (-3025 3625);
FORCEPROP 1 LAST PATH I217
J 0
(-3352 3750);
DISPLAY 0.872340 (-3352 3750);
PAINT GREEN (-3352 3750);
DISPLAY INVISIBLE (-3352 3750);
FORCEADD TAP..1
(-3150 3450);
FORCEPROP 3 LASTPIN (-3200 3450) SIG_NAME M_J_CPU1_SB_DQS_DN<8>
J 0
(-3190 3460);
DISPLAY 0.659574 (-3190 3460);
PAINT MONO (-3190 3460);
DISPLAY INVISIBLE (-3190 3460);
FORCEPROP 1 LASTPIN (-3200 3450) BN 8
J 0
(-3212 3458);
DISPLAY 0.489362 (-3212 3458);
PAINT GREEN (-3212 3458);
FORCEPROP 2 LAST CDS_LIB mstr_standard
J 0
(-3150 3450);
DISPLAY 0.723404 (-3150 3450);
PAINT MONO (-3150 3450);
DISPLAY INVISIBLE (-3150 3450);
FORCEPROP 1 LAST BODY_TYPE PLUMBING
J 0
(-3150 3500);
DISPLAY 0.872340 (-3150 3500);
PAINT GREEN (-3150 3500);
DISPLAY INVISIBLE (-3150 3500);
FORCEPROP 1 LAST HDL_TAP TRUE
J 0
(-2825 3325);
DISPLAY 0.872340 (-2825 3325);
DISPLAY INVISIBLE (-2825 3325);
FORCEPROP 1 LAST PATH I218
J 0
(-3152 3450);
DISPLAY 0.872340 (-3152 3450);
PAINT GREEN (-3152 3450);
DISPLAY INVISIBLE (-3152 3450);
FORCEADD TAP..1
(-3150 3350);
FORCEPROP 3 LASTPIN (-3200 3350) SIG_NAME M_J_CPU1_SB_DQS_DN<7>
J 0
(-3190 3360);
DISPLAY 0.659574 (-3190 3360);
PAINT MONO (-3190 3360);
DISPLAY INVISIBLE (-3190 3360);
FORCEPROP 1 LASTPIN (-3200 3350) BN 7
J 0
(-3212 3358);
DISPLAY 0.489362 (-3212 3358);
PAINT GREEN (-3212 3358);
FORCEPROP 2 LAST CDS_LIB mstr_standard
J 0
(-3150 3350);
DISPLAY 0.723404 (-3150 3350);
PAINT MONO (-3150 3350);
DISPLAY INVISIBLE (-3150 3350);
FORCEPROP 1 LAST BODY_TYPE PLUMBING
J 0
(-3150 3400);
DISPLAY 0.872340 (-3150 3400);
PAINT GREEN (-3150 3400);
DISPLAY INVISIBLE (-3150 3400);
FORCEPROP 1 LAST HDL_TAP TRUE
J 0
(-2825 3225);
DISPLAY 0.872340 (-2825 3225);
DISPLAY INVISIBLE (-2825 3225);
FORCEPROP 1 LAST PATH I219
J 0
(-3152 3350);
DISPLAY 0.872340 (-3152 3350);
PAINT GREEN (-3152 3350);
DISPLAY INVISIBLE (-3152 3350);
FORCEADD SCONN288_DDR506112002KQ..1
(-6700 3575);
FORCEPROP 1 LAST LOCATION J29
J 0
(-7150 5650);
DISPLAY 0.468085 (-7150 5650);
PAINT SKYBLUE (-7150 5650);
FORCEPROP 0 LAST $SEC 1
J 0
(-7150 5800);
DISPLAY 0.680851 (-7150 5800);
PAINT MONO (-7150 5800);
DISPLAY INVISIBLE (-7150 5800);
FORCEPROP 2 LAST CDS_SEC 1
J 0
(-7150 5800);
DISPLAY 1.021277 (-7150 5800);
DISPLAY INVISIBLE (-7150 5800);
FORCEPROP 0 LASTPIN (-7300 2975) $PN 62
J 2
(-7310 2985);
DISPLAY 0.680851 (-7310 2985);
PAINT MONO (-7310 2985);
FORCEPROP 0 LASTPIN (-7300 5025) $PN 66
J 2
(-7310 5035);
DISPLAY 0.680851 (-7310 5035);
PAINT MONO (-7310 5035);
FORCEPROP 0 LASTPIN (-7300 4625) $PN 76
J 2
(-7310 4635);
DISPLAY 0.680851 (-7310 4635);
PAINT MONO (-7310 4635);
FORCEPROP 0 LASTPIN (-7300 5075) $PN 211
J 2
(-7310 5085);
DISPLAY 0.680851 (-7310 5085);
PAINT MONO (-7310 5085);
FORCEPROP 0 LASTPIN (-7300 4675) $PN 221
J 2
(-7310 4685);
DISPLAY 0.680851 (-7310 4685);
PAINT MONO (-7310 4685);
FORCEPROP 0 LASTPIN (-7300 5125) $PN 68
J 2
(-7310 5135);
DISPLAY 0.680851 (-7310 5135);
PAINT MONO (-7310 5135);
FORCEPROP 0 LASTPIN (-7300 4725) $PN 78
J 2
(-7310 4735);
DISPLAY 0.680851 (-7310 4735);
PAINT MONO (-7310 4735);
FORCEPROP 0 LASTPIN (-7300 5175) $PN 213
J 2
(-7310 5185);
DISPLAY 0.680851 (-7310 5185);
PAINT MONO (-7310 5185);
FORCEPROP 0 LASTPIN (-7300 4775) $PN 223
J 2
(-7310 4785);
DISPLAY 0.680851 (-7310 4785);
PAINT MONO (-7310 4785);
FORCEPROP 0 LASTPIN (-7300 5225) $PN 70
J 2
(-7310 5235);
DISPLAY 0.680851 (-7310 5235);
PAINT MONO (-7310 5235);
FORCEPROP 0 LASTPIN (-7300 4825) $PN 80
J 2
(-7310 4835);
DISPLAY 0.680851 (-7310 4835);
PAINT MONO (-7310 4835);
FORCEPROP 0 LASTPIN (-7300 5275) $PN 215
J 2
(-7310 5285);
DISPLAY 0.680851 (-7310 5285);
PAINT MONO (-7310 5285);
FORCEPROP 0 LASTPIN (-7300 4875) $PN 225
J 2
(-7310 4885);
DISPLAY 0.680851 (-7310 4885);
PAINT MONO (-7310 4885);
FORCEPROP 0 LASTPIN (-7300 5325) $PN 72
J 2
(-7310 5335);
DISPLAY 0.680851 (-7310 5335);
PAINT MONO (-7310 5335);
FORCEPROP 0 LASTPIN (-7300 4925) $PN 82
J 2
(-7310 4935);
DISPLAY 0.680851 (-7310 4935);
PAINT MONO (-7310 4935);
FORCEPROP 0 LASTPIN (-7300 3575) $PN 51
J 2
(-7310 3585);
DISPLAY 0.680851 (-7310 3585);
PAINT MONO (-7310 3585);
FORCEPROP 0 LASTPIN (-7300 3125) $PN 96
J 2
(-7310 3135);
DISPLAY 0.680851 (-7310 3135);
PAINT MONO (-7310 3135);
FORCEPROP 0 LASTPIN (-7300 3625) $PN 53
J 2
(-7310 3635);
DISPLAY 0.680851 (-7310 3635);
PAINT MONO (-7310 3635);
FORCEPROP 0 LASTPIN (-7300 3175) $PN 98
J 2
(-7310 3185);
DISPLAY 0.680851 (-7310 3185);
PAINT MONO (-7310 3185);
FORCEPROP 0 LASTPIN (-7300 3675) $PN 196
J 2
(-7310 3685);
DISPLAY 0.680851 (-7310 3685);
PAINT MONO (-7310 3685);
FORCEPROP 0 LASTPIN (-7300 3225) $PN 241
J 2
(-7310 3235);
DISPLAY 0.680851 (-7310 3235);
PAINT MONO (-7310 3235);
FORCEPROP 0 LASTPIN (-7300 3725) $PN 198
J 2
(-7310 3735);
DISPLAY 0.680851 (-7310 3735);
PAINT MONO (-7310 3735);
FORCEPROP 0 LASTPIN (-7300 3275) $PN 243
J 2
(-7310 3285);
DISPLAY 0.680851 (-7310 3285);
PAINT MONO (-7310 3285);
FORCEPROP 0 LASTPIN (-7300 3775) $PN 58
J 2
(-7310 3785);
DISPLAY 0.680851 (-7310 3785);
PAINT MONO (-7310 3785);
FORCEPROP 0 LASTPIN (-7300 3325) $PN 89
J 2
(-7310 3335);
DISPLAY 0.680851 (-7310 3335);
PAINT MONO (-7310 3335);
FORCEPROP 0 LASTPIN (-7300 3825) $PN 60
J 2
(-7310 3835);
DISPLAY 0.680851 (-7310 3835);
PAINT MONO (-7310 3835);
FORCEPROP 0 LASTPIN (-7300 3375) $PN 91
J 2
(-7310 3385);
DISPLAY 0.680851 (-7310 3385);
PAINT MONO (-7310 3385);
FORCEPROP 0 LASTPIN (-7300 3875) $PN 203
J 2
(-7310 3885);
DISPLAY 0.680851 (-7310 3885);
PAINT MONO (-7310 3885);
FORCEPROP 0 LASTPIN (-7300 3425) $PN 234
J 2
(-7310 3435);
DISPLAY 0.680851 (-7310 3435);
PAINT MONO (-7310 3435);
FORCEPROP 0 LASTPIN (-7300 3925) $PN 205
J 2
(-7310 3935);
DISPLAY 0.680851 (-7310 3935);
PAINT MONO (-7310 3935);
FORCEPROP 0 LASTPIN (-7300 3475) $PN 236
J 2
(-7310 3485);
DISPLAY 0.680851 (-7310 3485);
PAINT MONO (-7310 3485);
FORCEPROP 0 LASTPIN (-7300 4025) $PN 218
J 2
(-7310 4035);
DISPLAY 0.680851 (-7310 4035);
PAINT MONO (-7310 4035);
FORCEPROP 0 LASTPIN (-7300 4075) $PN 217
J 2
(-7310 4085);
DISPLAY 0.680851 (-7310 4085);
PAINT MONO (-7310 4085);
FORCEPROP 0 LASTPIN (-7300 4325) $PN 64
J 2
(-7310 4335);
DISPLAY 0.680851 (-7310 4335);
PAINT MONO (-7310 4335);
FORCEPROP 0 LASTPIN (-7300 4175) $PN 84
J 2
(-7310 4185);
DISPLAY 0.680851 (-7310 4185);
PAINT MONO (-7310 4185);
FORCEPROP 0 LASTPIN (-7300 4375) $PN 209
J 2
(-7310 4385);
DISPLAY 0.680851 (-7310 4385);
PAINT MONO (-7310 4385);
FORCEPROP 0 LASTPIN (-7300 4225) $PN 229
J 2
(-7310 4235);
DISPLAY 0.680851 (-7310 4235);
PAINT MONO (-7310 4235);
FORCEPROP 0 LASTPIN (-6100 3775) $PN 7
J 0
(-6090 3785);
DISPLAY 0.680851 (-6090 3785);
PAINT MONO (-6090 3785);
FORCEPROP 0 LASTPIN (-6100 2125) $PN 100
J 0
(-6090 2135);
DISPLAY 0.680851 (-6090 2135);
PAINT MONO (-6090 2135);
FORCEPROP 0 LASTPIN (-6100 3825) $PN 9
J 0
(-6090 3835);
DISPLAY 0.680851 (-6090 3835);
PAINT MONO (-6090 3835);
FORCEPROP 0 LASTPIN (-6100 2175) $PN 102
J 0
(-6090 2185);
DISPLAY 0.680851 (-6090 2185);
PAINT MONO (-6090 2185);
FORCEPROP 0 LASTPIN (-6100 3875) $PN 152
J 0
(-6090 3885);
DISPLAY 0.680851 (-6090 3885);
PAINT MONO (-6090 3885);
FORCEPROP 0 LASTPIN (-6100 2225) $PN 245
J 0
(-6090 2235);
DISPLAY 0.680851 (-6090 2235);
PAINT MONO (-6090 2235);
FORCEPROP 0 LASTPIN (-6100 3925) $PN 154
J 0
(-6090 3935);
DISPLAY 0.680851 (-6090 3935);
PAINT MONO (-6090 3935);
FORCEPROP 0 LASTPIN (-6100 2275) $PN 247
J 0
(-6090 2285);
DISPLAY 0.680851 (-6090 2285);
PAINT MONO (-6090 2285);
FORCEPROP 0 LASTPIN (-6100 3975) $PN 14
J 0
(-6090 3985);
DISPLAY 0.680851 (-6090 3985);
PAINT MONO (-6090 3985);
FORCEPROP 0 LASTPIN (-6100 2325) $PN 107
J 0
(-6090 2335);
DISPLAY 0.680851 (-6090 2335);
PAINT MONO (-6090 2335);
FORCEPROP 0 LASTPIN (-6100 4025) $PN 16
J 0
(-6090 4035);
DISPLAY 0.680851 (-6090 4035);
PAINT MONO (-6090 4035);
FORCEPROP 0 LASTPIN (-6100 2375) $PN 109
J 0
(-6090 2385);
DISPLAY 0.680851 (-6090 2385);
PAINT MONO (-6090 2385);
FORCEPROP 0 LASTPIN (-6100 4075) $PN 159
J 0
(-6090 4085);
DISPLAY 0.680851 (-6090 4085);
PAINT MONO (-6090 4085);
FORCEPROP 0 LASTPIN (-6100 2425) $PN 252
J 0
(-6090 2435);
DISPLAY 0.680851 (-6090 2435);
PAINT MONO (-6090 2435);
FORCEPROP 0 LASTPIN (-6100 4125) $PN 161
J 0
(-6090 4135);
DISPLAY 0.680851 (-6090 4135);
PAINT MONO (-6090 4135);
FORCEPROP 0 LASTPIN (-6100 2475) $PN 254
J 0
(-6090 2485);
DISPLAY 0.680851 (-6090 2485);
PAINT MONO (-6090 2485);
FORCEPROP 0 LASTPIN (-6100 4175) $PN 18
J 0
(-6090 4185);
DISPLAY 0.680851 (-6090 4185);
PAINT MONO (-6090 4185);
FORCEPROP 0 LASTPIN (-6100 2525) $PN 111
J 0
(-6090 2535);
DISPLAY 0.680851 (-6090 2535);
PAINT MONO (-6090 2535);
FORCEPROP 0 LASTPIN (-6100 4225) $PN 20
J 0
(-6090 4235);
DISPLAY 0.680851 (-6090 4235);
PAINT MONO (-6090 4235);
FORCEPROP 0 LASTPIN (-6100 2575) $PN 113
J 0
(-6090 2585);
DISPLAY 0.680851 (-6090 2585);
PAINT MONO (-6090 2585);
FORCEPROP 0 LASTPIN (-6100 4275) $PN 163
J 0
(-6090 4285);
DISPLAY 0.680851 (-6090 4285);
PAINT MONO (-6090 4285);
FORCEPROP 0 LASTPIN (-6100 2625) $PN 256
J 0
(-6090 2635);
DISPLAY 0.680851 (-6090 2635);
PAINT MONO (-6090 2635);
FORCEPROP 0 LASTPIN (-6100 4325) $PN 165
J 0
(-6090 4335);
DISPLAY 0.680851 (-6090 4335);
PAINT MONO (-6090 4335);
FORCEPROP 0 LASTPIN (-6100 2675) $PN 258
J 0
(-6090 2685);
DISPLAY 0.680851 (-6090 2685);
PAINT MONO (-6090 2685);
FORCEPROP 0 LASTPIN (-6100 4375) $PN 25
J 0
(-6090 4385);
DISPLAY 0.680851 (-6090 4385);
PAINT MONO (-6090 4385);
FORCEPROP 0 LASTPIN (-6100 2725) $PN 118
J 0
(-6090 2735);
DISPLAY 0.680851 (-6090 2735);
PAINT MONO (-6090 2735);
FORCEPROP 0 LASTPIN (-6100 4425) $PN 27
J 0
(-6090 4435);
DISPLAY 0.680851 (-6090 4435);
PAINT MONO (-6090 4435);
FORCEPROP 0 LASTPIN (-6100 2775) $PN 120
J 0
(-6090 2785);
DISPLAY 0.680851 (-6090 2785);
PAINT MONO (-6090 2785);
FORCEPROP 0 LASTPIN (-6100 4475) $PN 170
J 0
(-6090 4485);
DISPLAY 0.680851 (-6090 4485);
PAINT MONO (-6090 4485);
FORCEPROP 0 LASTPIN (-6100 2825) $PN 263
J 0
(-6090 2835);
DISPLAY 0.680851 (-6090 2835);
PAINT MONO (-6090 2835);
FORCEPROP 0 LASTPIN (-6100 4525) $PN 172
J 0
(-6090 4535);
DISPLAY 0.680851 (-6090 4535);
PAINT MONO (-6090 4535);
FORCEPROP 0 LASTPIN (-6100 2875) $PN 265
J 0
(-6090 2885);
DISPLAY 0.680851 (-6090 2885);
PAINT MONO (-6090 2885);
FORCEPROP 0 LASTPIN (-6100 4575) $PN 29
J 0
(-6090 4585);
DISPLAY 0.680851 (-6090 4585);
PAINT MONO (-6090 4585);
FORCEPROP 0 LASTPIN (-6100 2925) $PN 122
J 0
(-6090 2935);
DISPLAY 0.680851 (-6090 2935);
PAINT MONO (-6090 2935);
FORCEPROP 0 LASTPIN (-6100 4625) $PN 31
J 0
(-6090 4635);
DISPLAY 0.680851 (-6090 4635);
PAINT MONO (-6090 4635);
FORCEPROP 0 LASTPIN (-6100 2975) $PN 124
J 0
(-6090 2985);
DISPLAY 0.680851 (-6090 2985);
PAINT MONO (-6090 2985);
FORCEPROP 0 LASTPIN (-6100 4675) $PN 174
J 0
(-6090 4685);
DISPLAY 0.680851 (-6090 4685);
PAINT MONO (-6090 4685);
FORCEPROP 0 LASTPIN (-6100 3025) $PN 267
J 0
(-6090 3035);
DISPLAY 0.680851 (-6090 3035);
PAINT MONO (-6090 3035);
FORCEPROP 0 LASTPIN (-6100 4725) $PN 176
J 0
(-6090 4735);
DISPLAY 0.680851 (-6090 4735);
PAINT MONO (-6090 4735);
FORCEPROP 0 LASTPIN (-6100 3075) $PN 269
J 0
(-6090 3085);
DISPLAY 0.680851 (-6090 3085);
PAINT MONO (-6090 3085);
FORCEPROP 0 LASTPIN (-6100 4775) $PN 36
J 0
(-6090 4785);
DISPLAY 0.680851 (-6090 4785);
PAINT MONO (-6090 4785);
FORCEPROP 0 LASTPIN (-6100 3125) $PN 129
J 0
(-6090 3135);
DISPLAY 0.680851 (-6090 3135);
PAINT MONO (-6090 3135);
FORCEPROP 0 LASTPIN (-6100 4825) $PN 38
J 0
(-6090 4835);
DISPLAY 0.680851 (-6090 4835);
PAINT MONO (-6090 4835);
FORCEPROP 0 LASTPIN (-6100 3175) $PN 131
J 0
(-6090 3185);
DISPLAY 0.680851 (-6090 3185);
PAINT MONO (-6090 3185);
FORCEPROP 0 LASTPIN (-6100 4875) $PN 181
J 0
(-6090 4885);
DISPLAY 0.680851 (-6090 4885);
PAINT MONO (-6090 4885);
FORCEPROP 0 LASTPIN (-6100 3225) $PN 274
J 0
(-6090 3235);
DISPLAY 0.680851 (-6090 3235);
PAINT MONO (-6090 3235);
FORCEPROP 0 LASTPIN (-6100 4925) $PN 183
J 0
(-6090 4935);
DISPLAY 0.680851 (-6090 4935);
PAINT MONO (-6090 4935);
FORCEPROP 0 LASTPIN (-6100 3275) $PN 276
J 0
(-6090 3285);
DISPLAY 0.680851 (-6090 3285);
PAINT MONO (-6090 3285);
FORCEPROP 0 LASTPIN (-6100 4975) $PN 40
J 0
(-6090 4985);
DISPLAY 0.680851 (-6090 4985);
PAINT MONO (-6090 4985);
FORCEPROP 0 LASTPIN (-6100 3325) $PN 133
J 0
(-6090 3335);
DISPLAY 0.680851 (-6090 3335);
PAINT MONO (-6090 3335);
FORCEPROP 0 LASTPIN (-6100 5025) $PN 42
J 0
(-6090 5035);
DISPLAY 0.680851 (-6090 5035);
PAINT MONO (-6090 5035);
FORCEPROP 0 LASTPIN (-6100 3375) $PN 135
J 0
(-6090 3385);
DISPLAY 0.680851 (-6090 3385);
PAINT MONO (-6090 3385);
FORCEPROP 0 LASTPIN (-6100 5075) $PN 185
J 0
(-6090 5085);
DISPLAY 0.680851 (-6090 5085);
PAINT MONO (-6090 5085);
FORCEPROP 0 LASTPIN (-6100 3425) $PN 278
J 0
(-6090 3435);
DISPLAY 0.680851 (-6090 3435);
PAINT MONO (-6090 3435);
FORCEPROP 0 LASTPIN (-6100 5125) $PN 187
J 0
(-6090 5135);
DISPLAY 0.680851 (-6090 5135);
PAINT MONO (-6090 5135);
FORCEPROP 0 LASTPIN (-6100 3475) $PN 280
J 0
(-6090 3485);
DISPLAY 0.680851 (-6090 3485);
PAINT MONO (-6090 3485);
FORCEPROP 0 LASTPIN (-6100 5175) $PN 47
J 0
(-6090 5185);
DISPLAY 0.680851 (-6090 5185);
PAINT MONO (-6090 5185);
FORCEPROP 0 LASTPIN (-6100 3525) $PN 140
J 0
(-6090 3535);
DISPLAY 0.680851 (-6090 3535);
PAINT MONO (-6090 3535);
FORCEPROP 0 LASTPIN (-6100 5225) $PN 49
J 0
(-6090 5235);
DISPLAY 0.680851 (-6090 5235);
PAINT MONO (-6090 5235);
FORCEPROP 0 LASTPIN (-6100 3575) $PN 142
J 0
(-6090 3585);
DISPLAY 0.680851 (-6090 3585);
PAINT MONO (-6090 3585);
FORCEPROP 0 LASTPIN (-6100 5275) $PN 192
J 0
(-6090 5285);
DISPLAY 0.680851 (-6090 5285);
PAINT MONO (-6090 5285);
FORCEPROP 0 LASTPIN (-6100 3625) $PN 285
J 0
(-6090 3635);
DISPLAY 0.680851 (-6090 3635);
PAINT MONO (-6090 3635);
FORCEPROP 0 LASTPIN (-6100 5325) $PN 194
J 0
(-6090 5335);
DISPLAY 0.680851 (-6090 5335);
PAINT MONO (-6090 5335);
FORCEPROP 0 LASTPIN (-6100 3675) $PN 287
J 0
(-6090 3685);
DISPLAY 0.680851 (-6090 3685);
PAINT MONO (-6090 3685);
FORCEPROP 0 LASTPIN (-7300 2825) $PN 148
J 2
(-7310 2835);
DISPLAY 0.680851 (-7310 2835);
PAINT MONO (-7310 2835);
FORCEPROP 0 LASTPIN (-7300 2725) $PN 4
J 2
(-7310 2735);
DISPLAY 0.680851 (-7310 2735);
PAINT MONO (-7310 2735);
FORCEPROP 0 LASTPIN (-7300 2775) $PN 5
J 2
(-7310 2785);
DISPLAY 0.680851 (-7310 2785);
PAINT MONO (-7310 2785);
FORCEPROP 0 LASTPIN (-7300 1925) $PN 86
J 2
(-7310 1935);
DISPLAY 0.680851 (-7310 1935);
PAINT MONO (-7310 1935);
FORCEPROP 0 LASTPIN (-7300 1875) $PN 87
J 2
(-7310 1885);
DISPLAY 0.680851 (-7310 1885);
PAINT MONO (-7310 1885);
FORCEPROP 0 LASTPIN (-7300 4525) $PN 74
J 2
(-7310 4535);
DISPLAY 0.680851 (-7310 4535);
PAINT MONO (-7310 4535);
FORCEPROP 0 LASTPIN (-7300 4475) $PN 227
J 2
(-7310 4485);
DISPLAY 0.680851 (-7310 4485);
PAINT MONO (-7310 4485);
FORCEPROP 0 LASTPIN (-7300 2475) $PN 147
J 2
(-7310 2485);
DISPLAY 0.680851 (-7310 2485);
PAINT MONO (-7310 2485);
FORCEPROP 0 LASTPIN (-7300 3025) $PN 207
J 2
(-7310 3035);
DISPLAY 0.680851 (-7310 3035);
PAINT MONO (-7310 3035);
FORCEPROP 0 LASTPIN (-7300 2075) $PN 2
J 2
(-7310 2085);
DISPLAY 0.680851 (-7310 2085);
PAINT MONO (-7310 2085);
FORCEPROP 0 LASTPIN (-7300 2125) $PN 144
J 2
(-7310 2135);
DISPLAY 0.680851 (-7310 2135);
PAINT MONO (-7310 2135);
FORCEPROP 0 LASTPIN (-7300 2175) $PN 149
J 2
(-7310 2185);
DISPLAY 0.680851 (-7310 2185);
PAINT MONO (-7310 2185);
FORCEPROP 0 LASTPIN (-7300 2225) $PN 150
J 2
(-7310 2235);
DISPLAY 0.680851 (-7310 2235);
PAINT MONO (-7310 2235);
FORCEPROP 0 LASTPIN (-7300 2275) $PN 220
J 2
(-7310 2285);
DISPLAY 0.680851 (-7310 2285);
PAINT MONO (-7310 2285);
FORCEPROP 0 LASTPIN (-7300 2325) $PN 231
J 2
(-7310 2335);
DISPLAY 0.680851 (-7310 2335);
PAINT MONO (-7310 2335);
FORCEPROP 0 LASTPIN (-7300 2375) $PN 232
J 2
(-7310 2385);
DISPLAY 0.680851 (-7310 2385);
PAINT MONO (-7310 2385);
FORCEPROP 0 LASTPIN (-7300 2875) $PN 3
J 2
(-7310 2885);
DISPLAY 0.680851 (-7310 2885);
PAINT MONO (-7310 2885);
FORCEPROP 2 LAST PART_TYPE SMLF
J 0
(-7150 5750);
DISPLAY 1.021277 (-7150 5750);
FORCEPROP 2 LAST VALUE SCONN288_DDR506112002KQ
J 0
(-7150 5700);
DISPLAY 0.489362 (-7150 5700);
PAINT SKYBLUE (-7150 5700);
FORCEPROP 1 LAST MATERIAL IO
J 0
(-7150 5500);
DISPLAY 0.468085 (-7150 5500);
PAINT SKYBLUE (-7150 5500);
FORCEPROP 1 LAST PART_NUMBER DFHST8FS479
J 0
(-7150 5575);
DISPLAY 0.468085 (-7150 5575);
PAINT SKYBLUE (-7150 5575);
FORCEPROP 1 LAST CDS_LMAN_SYM_OUTLINE -450,1900,450,-1850
J 0
(-6700 3575);
DISPLAY 0.468085 (-6700 3575);
PAINT GREEN (-6700 3575);
DISPLAY INVISIBLE (-6700 3575);
FORCEPROP 1 LAST PATH I22
J 0
(-6700 3575);
DISPLAY 0.723404 (-6700 3575);
PAINT GREEN (-6700 3575);
DISPLAY INVISIBLE (-6700 3575);
FORCEPROP 1 LAST NEEDS_NO_SIZE TRUE
J 0
(-6700 3575);
DISPLAY 0.723404 (-6700 3575);
PAINT GREEN (-6700 3575);
DISPLAY INVISIBLE (-6700 3575);
FORCEPROP 2 LAST CDS_LIB pure_quanta
J 0
(-6700 3575);
DISPLAY INVISIBLE (-6700 3575);
FORCEADD TAP..1
(-3150 3150);
FORCEPROP 3 LASTPIN (-3200 3150) SIG_NAME M_J_CPU1_SB_DQS_DN<5>
J 0
(-3190 3160);
DISPLAY 0.659574 (-3190 3160);
PAINT MONO (-3190 3160);
DISPLAY INVISIBLE (-3190 3160);
FORCEPROP 1 LASTPIN (-3200 3150) BN 5
J 0
(-3212 3158);
DISPLAY 0.489362 (-3212 3158);
PAINT GREEN (-3212 3158);
FORCEPROP 2 LAST CDS_LIB mstr_standard
J 0
(-3150 3150);
DISPLAY 0.723404 (-3150 3150);
PAINT MONO (-3150 3150);
DISPLAY INVISIBLE (-3150 3150);
FORCEPROP 1 LAST BODY_TYPE PLUMBING
J 0
(-3150 3200);
DISPLAY 0.872340 (-3150 3200);
PAINT GREEN (-3150 3200);
DISPLAY INVISIBLE (-3150 3200);
FORCEPROP 1 LAST HDL_TAP TRUE
J 0
(-2825 3025);
DISPLAY 0.872340 (-2825 3025);
DISPLAY INVISIBLE (-2825 3025);
FORCEPROP 1 LAST PATH I220
J 0
(-3152 3150);
DISPLAY 0.872340 (-3152 3150);
PAINT GREEN (-3152 3150);
DISPLAY INVISIBLE (-3152 3150);
FORCEADD TAP..1
(-3150 3250);
FORCEPROP 3 LASTPIN (-3200 3250) SIG_NAME M_J_CPU1_SB_DQS_DN<6>
J 0
(-3190 3260);
DISPLAY 0.659574 (-3190 3260);
PAINT MONO (-3190 3260);
DISPLAY INVISIBLE (-3190 3260);
FORCEPROP 1 LASTPIN (-3200 3250) BN 6
J 0
(-3212 3258);
DISPLAY 0.489362 (-3212 3258);
PAINT GREEN (-3212 3258);
FORCEPROP 2 LAST CDS_LIB mstr_standard
J 0
(-3150 3250);
DISPLAY 0.723404 (-3150 3250);
PAINT MONO (-3150 3250);
DISPLAY INVISIBLE (-3150 3250);
FORCEPROP 1 LAST BODY_TYPE PLUMBING
J 0
(-3150 3300);
DISPLAY 0.872340 (-3150 3300);
PAINT GREEN (-3150 3300);
DISPLAY INVISIBLE (-3150 3300);
FORCEPROP 1 LAST HDL_TAP TRUE
J 0
(-2825 3125);
DISPLAY 0.872340 (-2825 3125);
DISPLAY INVISIBLE (-2825 3125);
FORCEPROP 1 LAST PATH I221
J 0
(-3152 3250);
DISPLAY 0.872340 (-3152 3250);
PAINT GREEN (-3152 3250);
DISPLAY INVISIBLE (-3152 3250);
FORCEADD TAP..1
(-3150 3050);
FORCEPROP 3 LASTPIN (-3200 3050) SIG_NAME M_J_CPU1_SB_DQS_DN<4>
J 0
(-3190 3060);
DISPLAY 0.659574 (-3190 3060);
PAINT MONO (-3190 3060);
DISPLAY INVISIBLE (-3190 3060);
FORCEPROP 1 LASTPIN (-3200 3050) BN 4
J 0
(-3212 3058);
DISPLAY 0.489362 (-3212 3058);
PAINT GREEN (-3212 3058);
FORCEPROP 2 LAST CDS_LIB mstr_standard
J 0
(-3150 3050);
DISPLAY 0.723404 (-3150 3050);
PAINT MONO (-3150 3050);
DISPLAY INVISIBLE (-3150 3050);
FORCEPROP 1 LAST BODY_TYPE PLUMBING
J 0
(-3150 3100);
DISPLAY 0.872340 (-3150 3100);
PAINT GREEN (-3150 3100);
DISPLAY INVISIBLE (-3150 3100);
FORCEPROP 1 LAST HDL_TAP TRUE
J 0
(-2825 2925);
DISPLAY 0.872340 (-2825 2925);
DISPLAY INVISIBLE (-2825 2925);
FORCEPROP 1 LAST PATH I222
J 0
(-3152 3050);
DISPLAY 0.872340 (-3152 3050);
PAINT GREEN (-3152 3050);
DISPLAY INVISIBLE (-3152 3050);
FORCEADD TAP..1
(-3150 2950);
FORCEPROP 3 LASTPIN (-3200 2950) SIG_NAME M_J_CPU1_SB_DQS_DN<3>
J 0
(-3190 2960);
DISPLAY 0.659574 (-3190 2960);
PAINT MONO (-3190 2960);
DISPLAY INVISIBLE (-3190 2960);
FORCEPROP 1 LASTPIN (-3200 2950) BN 3
J 0
(-3212 2958);
DISPLAY 0.489362 (-3212 2958);
PAINT GREEN (-3212 2958);
FORCEPROP 2 LAST CDS_LIB mstr_standard
J 0
(-3150 2950);
DISPLAY 0.723404 (-3150 2950);
PAINT MONO (-3150 2950);
DISPLAY INVISIBLE (-3150 2950);
FORCEPROP 1 LAST BODY_TYPE PLUMBING
J 0
(-3150 3000);
DISPLAY 0.872340 (-3150 3000);
PAINT GREEN (-3150 3000);
DISPLAY INVISIBLE (-3150 3000);
FORCEPROP 1 LAST HDL_TAP TRUE
J 0
(-2825 2825);
DISPLAY 0.872340 (-2825 2825);
DISPLAY INVISIBLE (-2825 2825);
FORCEPROP 1 LAST PATH I223
J 0
(-3152 2950);
DISPLAY 0.872340 (-3152 2950);
PAINT GREEN (-3152 2950);
DISPLAY INVISIBLE (-3152 2950);
FORCEADD TAP..1
(-3150 2850);
FORCEPROP 3 LASTPIN (-3200 2850) SIG_NAME M_J_CPU1_SB_DQS_DN<2>
J 0
(-3190 2860);
DISPLAY 0.659574 (-3190 2860);
PAINT MONO (-3190 2860);
DISPLAY INVISIBLE (-3190 2860);
FORCEPROP 1 LASTPIN (-3200 2850) BN 2
J 0
(-3212 2858);
DISPLAY 0.489362 (-3212 2858);
PAINT GREEN (-3212 2858);
FORCEPROP 2 LAST CDS_LIB mstr_standard
J 0
(-3150 2850);
DISPLAY 0.723404 (-3150 2850);
PAINT MONO (-3150 2850);
DISPLAY INVISIBLE (-3150 2850);
FORCEPROP 1 LAST BODY_TYPE PLUMBING
J 0
(-3150 2900);
DISPLAY 0.872340 (-3150 2900);
PAINT GREEN (-3150 2900);
DISPLAY INVISIBLE (-3150 2900);
FORCEPROP 1 LAST HDL_TAP TRUE
J 0
(-2825 2725);
DISPLAY 0.872340 (-2825 2725);
DISPLAY INVISIBLE (-2825 2725);
FORCEPROP 1 LAST PATH I224
J 0
(-3152 2850);
DISPLAY 0.872340 (-3152 2850);
PAINT GREEN (-3152 2850);
DISPLAY INVISIBLE (-3152 2850);
FORCEADD TAP..1
(-3150 2750);
FORCEPROP 3 LASTPIN (-3200 2750) SIG_NAME M_J_CPU1_SB_DQS_DN<1>
J 0
(-3190 2760);
DISPLAY 0.659574 (-3190 2760);
PAINT MONO (-3190 2760);
DISPLAY INVISIBLE (-3190 2760);
FORCEPROP 1 LASTPIN (-3200 2750) BN 1
J 0
(-3212 2758);
DISPLAY 0.489362 (-3212 2758);
PAINT GREEN (-3212 2758);
FORCEPROP 2 LAST CDS_LIB mstr_standard
J 0
(-3150 2750);
DISPLAY 0.723404 (-3150 2750);
PAINT MONO (-3150 2750);
DISPLAY INVISIBLE (-3150 2750);
FORCEPROP 1 LAST BODY_TYPE PLUMBING
J 0
(-3150 2800);
DISPLAY 0.872340 (-3150 2800);
PAINT GREEN (-3150 2800);
DISPLAY INVISIBLE (-3150 2800);
FORCEPROP 1 LAST HDL_TAP TRUE
J 0
(-2825 2625);
DISPLAY 0.872340 (-2825 2625);
DISPLAY INVISIBLE (-2825 2625);
FORCEPROP 1 LAST PATH I225
J 0
(-3152 2750);
DISPLAY 0.872340 (-3152 2750);
PAINT GREEN (-3152 2750);
DISPLAY INVISIBLE (-3152 2750);
FORCEADD TAP..1
(-3150 2650);
FORCEPROP 3 LASTPIN (-3200 2650) SIG_NAME M_J_CPU1_SB_DQS_DN<0>
J 0
(-3190 2660);
DISPLAY 0.659574 (-3190 2660);
PAINT MONO (-3190 2660);
DISPLAY INVISIBLE (-3190 2660);
FORCEPROP 1 LASTPIN (-3200 2650) BN 0
J 0
(-3212 2658);
DISPLAY 0.489362 (-3212 2658);
PAINT GREEN (-3212 2658);
FORCEPROP 2 LAST CDS_LIB mstr_standard
J 0
(-3150 2650);
DISPLAY 0.723404 (-3150 2650);
PAINT MONO (-3150 2650);
DISPLAY INVISIBLE (-3150 2650);
FORCEPROP 1 LAST BODY_TYPE PLUMBING
J 0
(-3150 2700);
DISPLAY 0.872340 (-3150 2700);
PAINT GREEN (-3150 2700);
DISPLAY INVISIBLE (-3150 2700);
FORCEPROP 1 LAST HDL_TAP TRUE
J 0
(-2825 2525);
DISPLAY 0.872340 (-2825 2525);
DISPLAY INVISIBLE (-2825 2525);
FORCEPROP 1 LAST PATH I226
J 0
(-3152 2650);
DISPLAY 0.872340 (-3152 2650);
PAINT GREEN (-3152 2650);
DISPLAY INVISIBLE (-3152 2650);
FORCEADD TAP..1
(-3350 3500);
FORCEPROP 3 LASTPIN (-3400 3500) SIG_NAME M_J_CPU1_SB_DQS_DP<8>
J 0
(-3390 3510);
DISPLAY 0.659574 (-3390 3510);
PAINT MONO (-3390 3510);
DISPLAY INVISIBLE (-3390 3510);
FORCEPROP 1 LASTPIN (-3400 3500) BN 8
J 0
(-3412 3508);
DISPLAY 0.489362 (-3412 3508);
PAINT GREEN (-3412 3508);
FORCEPROP 2 LAST CDS_LIB mstr_standard
J 0
(-3350 3500);
DISPLAY 0.723404 (-3350 3500);
PAINT MONO (-3350 3500);
DISPLAY INVISIBLE (-3350 3500);
FORCEPROP 1 LAST BODY_TYPE PLUMBING
J 0
(-3350 3550);
DISPLAY 0.872340 (-3350 3550);
PAINT GREEN (-3350 3550);
DISPLAY INVISIBLE (-3350 3550);
FORCEPROP 1 LAST HDL_TAP TRUE
J 0
(-3025 3375);
DISPLAY 0.872340 (-3025 3375);
DISPLAY INVISIBLE (-3025 3375);
FORCEPROP 1 LAST PATH I227
J 0
(-3352 3500);
DISPLAY 0.872340 (-3352 3500);
PAINT GREEN (-3352 3500);
DISPLAY INVISIBLE (-3352 3500);
FORCEADD TAP..1
(-3350 3400);
FORCEPROP 3 LASTPIN (-3400 3400) SIG_NAME M_J_CPU1_SB_DQS_DP<7>
J 0
(-3390 3410);
DISPLAY 0.659574 (-3390 3410);
PAINT MONO (-3390 3410);
DISPLAY INVISIBLE (-3390 3410);
FORCEPROP 1 LASTPIN (-3400 3400) BN 7
J 0
(-3412 3408);
DISPLAY 0.489362 (-3412 3408);
PAINT GREEN (-3412 3408);
FORCEPROP 2 LAST CDS_LIB mstr_standard
J 0
(-3350 3400);
DISPLAY 0.723404 (-3350 3400);
PAINT MONO (-3350 3400);
DISPLAY INVISIBLE (-3350 3400);
FORCEPROP 1 LAST BODY_TYPE PLUMBING
J 0
(-3350 3450);
DISPLAY 0.872340 (-3350 3450);
PAINT GREEN (-3350 3450);
DISPLAY INVISIBLE (-3350 3450);
FORCEPROP 1 LAST HDL_TAP TRUE
J 0
(-3025 3275);
DISPLAY 0.872340 (-3025 3275);
DISPLAY INVISIBLE (-3025 3275);
FORCEPROP 1 LAST PATH I228
J 0
(-3352 3400);
DISPLAY 0.872340 (-3352 3400);
PAINT GREEN (-3352 3400);
DISPLAY INVISIBLE (-3352 3400);
FORCEADD TAP..1
(-3350 3300);
FORCEPROP 3 LASTPIN (-3400 3300) SIG_NAME M_J_CPU1_SB_DQS_DP<6>
J 0
(-3390 3310);
DISPLAY 0.659574 (-3390 3310);
PAINT MONO (-3390 3310);
DISPLAY INVISIBLE (-3390 3310);
FORCEPROP 1 LASTPIN (-3400 3300) BN 6
J 0
(-3412 3308);
DISPLAY 0.489362 (-3412 3308);
PAINT GREEN (-3412 3308);
FORCEPROP 2 LAST CDS_LIB mstr_standard
J 0
(-3350 3300);
DISPLAY 0.723404 (-3350 3300);
PAINT MONO (-3350 3300);
DISPLAY INVISIBLE (-3350 3300);
FORCEPROP 1 LAST BODY_TYPE PLUMBING
J 0
(-3350 3350);
DISPLAY 0.872340 (-3350 3350);
PAINT GREEN (-3350 3350);
DISPLAY INVISIBLE (-3350 3350);
FORCEPROP 1 LAST HDL_TAP TRUE
J 0
(-3025 3175);
DISPLAY 0.872340 (-3025 3175);
DISPLAY INVISIBLE (-3025 3175);
FORCEPROP 1 LAST PATH I229
J 0
(-3352 3300);
DISPLAY 0.872340 (-3352 3300);
PAINT GREEN (-3352 3300);
DISPLAY INVISIBLE (-3352 3300);
FORCEADD TAP..1
R 2
(-7550 3125);
FORCEPROP 3 LASTPIN (-7500 3125) SIG_NAME M_J_CPU1_SB_CB<0>
J 0
(-7490 3135);
DISPLAY 0.659574 (-7490 3135);
PAINT MONO (-7490 3135);
DISPLAY INVISIBLE (-7490 3135);
FORCEPROP 1 LASTPIN (-7500 3125) BN 0
J 2
(-7488 3133);
DISPLAY 0.489362 (-7488 3133);
PAINT GREEN (-7488 3133);
FORCEPROP 2 LAST CDS_LIB mstr_standard
J 0
(-7550 3125);
DISPLAY 0.723404 (-7550 3125);
PAINT MONO (-7550 3125);
DISPLAY INVISIBLE (-7550 3125);
FORCEPROP 1 LAST BODY_TYPE PLUMBING
J 2
(-7550 3175);
DISPLAY 0.872340 (-7550 3175);
PAINT GREEN (-7550 3175);
DISPLAY INVISIBLE (-7550 3175);
FORCEPROP 1 LAST HDL_TAP TRUE
J 2
(-7875 3000);
DISPLAY 0.872340 (-7875 3000);
DISPLAY INVISIBLE (-7875 3000);
FORCEPROP 1 LAST PATH I23
J 2
(-7548 3125);
DISPLAY 0.872340 (-7548 3125);
PAINT GREEN (-7548 3125);
DISPLAY INVISIBLE (-7548 3125);
FORCEADD TAP..1
(-3350 3200);
FORCEPROP 3 LASTPIN (-3400 3200) SIG_NAME M_J_CPU1_SB_DQS_DP<5>
J 0
(-3390 3210);
DISPLAY 0.659574 (-3390 3210);
PAINT MONO (-3390 3210);
DISPLAY INVISIBLE (-3390 3210);
FORCEPROP 1 LASTPIN (-3400 3200) BN 5
J 0
(-3412 3208);
DISPLAY 0.489362 (-3412 3208);
PAINT GREEN (-3412 3208);
FORCEPROP 2 LAST CDS_LIB mstr_standard
J 0
(-3350 3200);
DISPLAY 0.723404 (-3350 3200);
PAINT MONO (-3350 3200);
DISPLAY INVISIBLE (-3350 3200);
FORCEPROP 1 LAST BODY_TYPE PLUMBING
J 0
(-3350 3250);
DISPLAY 0.872340 (-3350 3250);
PAINT GREEN (-3350 3250);
DISPLAY INVISIBLE (-3350 3250);
FORCEPROP 1 LAST HDL_TAP TRUE
J 0
(-3025 3075);
DISPLAY 0.872340 (-3025 3075);
DISPLAY INVISIBLE (-3025 3075);
FORCEPROP 1 LAST PATH I230
J 0
(-3352 3200);
DISPLAY 0.872340 (-3352 3200);
PAINT GREEN (-3352 3200);
DISPLAY INVISIBLE (-3352 3200);
FORCEADD TAP..1
(-3350 3100);
FORCEPROP 3 LASTPIN (-3400 3100) SIG_NAME M_J_CPU1_SB_DQS_DP<4>
J 0
(-3390 3110);
DISPLAY 0.659574 (-3390 3110);
PAINT MONO (-3390 3110);
DISPLAY INVISIBLE (-3390 3110);
FORCEPROP 1 LASTPIN (-3400 3100) BN 4
J 0
(-3412 3108);
DISPLAY 0.489362 (-3412 3108);
PAINT GREEN (-3412 3108);
FORCEPROP 2 LAST CDS_LIB mstr_standard
J 0
(-3350 3100);
DISPLAY 0.723404 (-3350 3100);
PAINT MONO (-3350 3100);
DISPLAY INVISIBLE (-3350 3100);
FORCEPROP 1 LAST BODY_TYPE PLUMBING
J 0
(-3350 3150);
DISPLAY 0.872340 (-3350 3150);
PAINT GREEN (-3350 3150);
DISPLAY INVISIBLE (-3350 3150);
FORCEPROP 1 LAST HDL_TAP TRUE
J 0
(-3025 2975);
DISPLAY 0.872340 (-3025 2975);
DISPLAY INVISIBLE (-3025 2975);
FORCEPROP 1 LAST PATH I231
J 0
(-3352 3100);
DISPLAY 0.872340 (-3352 3100);
PAINT GREEN (-3352 3100);
DISPLAY INVISIBLE (-3352 3100);
FORCEADD TAP..1
(-3350 2900);
FORCEPROP 3 LASTPIN (-3400 2900) SIG_NAME M_J_CPU1_SB_DQS_DP<2>
J 0
(-3390 2910);
DISPLAY 0.659574 (-3390 2910);
PAINT MONO (-3390 2910);
DISPLAY INVISIBLE (-3390 2910);
FORCEPROP 1 LASTPIN (-3400 2900) BN 2
J 0
(-3412 2908);
DISPLAY 0.489362 (-3412 2908);
PAINT GREEN (-3412 2908);
FORCEPROP 2 LAST CDS_LIB mstr_standard
J 0
(-3350 2900);
DISPLAY 0.723404 (-3350 2900);
PAINT MONO (-3350 2900);
DISPLAY INVISIBLE (-3350 2900);
FORCEPROP 1 LAST BODY_TYPE PLUMBING
J 0
(-3350 2950);
DISPLAY 0.872340 (-3350 2950);
PAINT GREEN (-3350 2950);
DISPLAY INVISIBLE (-3350 2950);
FORCEPROP 1 LAST HDL_TAP TRUE
J 0
(-3025 2775);
DISPLAY 0.872340 (-3025 2775);
DISPLAY INVISIBLE (-3025 2775);
FORCEPROP 1 LAST PATH I232
J 0
(-3352 2900);
DISPLAY 0.872340 (-3352 2900);
PAINT GREEN (-3352 2900);
DISPLAY INVISIBLE (-3352 2900);
FORCEADD TAP..1
(-3350 3000);
FORCEPROP 3 LASTPIN (-3400 3000) SIG_NAME M_J_CPU1_SB_DQS_DP<3>
J 0
(-3390 3010);
DISPLAY 0.659574 (-3390 3010);
PAINT MONO (-3390 3010);
DISPLAY INVISIBLE (-3390 3010);
FORCEPROP 1 LASTPIN (-3400 3000) BN 3
J 0
(-3412 3008);
DISPLAY 0.489362 (-3412 3008);
PAINT GREEN (-3412 3008);
FORCEPROP 2 LAST CDS_LIB mstr_standard
J 0
(-3350 3000);
DISPLAY 0.723404 (-3350 3000);
PAINT MONO (-3350 3000);
DISPLAY INVISIBLE (-3350 3000);
FORCEPROP 1 LAST BODY_TYPE PLUMBING
J 0
(-3350 3050);
DISPLAY 0.872340 (-3350 3050);
PAINT GREEN (-3350 3050);
DISPLAY INVISIBLE (-3350 3050);
FORCEPROP 1 LAST HDL_TAP TRUE
J 0
(-3025 2875);
DISPLAY 0.872340 (-3025 2875);
DISPLAY INVISIBLE (-3025 2875);
FORCEPROP 1 LAST PATH I233
J 0
(-3352 3000);
DISPLAY 0.872340 (-3352 3000);
PAINT GREEN (-3352 3000);
DISPLAY INVISIBLE (-3352 3000);
FORCEADD TAP..1
(-3350 2800);
FORCEPROP 3 LASTPIN (-3400 2800) SIG_NAME M_J_CPU1_SB_DQS_DP<1>
J 0
(-3390 2810);
DISPLAY 0.659574 (-3390 2810);
PAINT MONO (-3390 2810);
DISPLAY INVISIBLE (-3390 2810);
FORCEPROP 1 LASTPIN (-3400 2800) BN 1
J 0
(-3412 2808);
DISPLAY 0.489362 (-3412 2808);
PAINT GREEN (-3412 2808);
FORCEPROP 2 LAST CDS_LIB mstr_standard
J 0
(-3350 2800);
DISPLAY 0.723404 (-3350 2800);
PAINT MONO (-3350 2800);
DISPLAY INVISIBLE (-3350 2800);
FORCEPROP 1 LAST BODY_TYPE PLUMBING
J 0
(-3350 2850);
DISPLAY 0.872340 (-3350 2850);
PAINT GREEN (-3350 2850);
DISPLAY INVISIBLE (-3350 2850);
FORCEPROP 1 LAST HDL_TAP TRUE
J 0
(-3025 2675);
DISPLAY 0.872340 (-3025 2675);
DISPLAY INVISIBLE (-3025 2675);
FORCEPROP 1 LAST PATH I234
J 0
(-3352 2800);
DISPLAY 0.872340 (-3352 2800);
PAINT GREEN (-3352 2800);
DISPLAY INVISIBLE (-3352 2800);
FORCEADD TAP..1
(-3350 2700);
FORCEPROP 3 LASTPIN (-3400 2700) SIG_NAME M_J_CPU1_SB_DQS_DP<0>
J 0
(-3390 2710);
DISPLAY 0.659574 (-3390 2710);
PAINT MONO (-3390 2710);
DISPLAY INVISIBLE (-3390 2710);
FORCEPROP 1 LASTPIN (-3400 2700) BN 0
J 0
(-3412 2708);
DISPLAY 0.489362 (-3412 2708);
PAINT GREEN (-3412 2708);
FORCEPROP 2 LAST CDS_LIB mstr_standard
J 0
(-3350 2700);
DISPLAY 0.723404 (-3350 2700);
PAINT MONO (-3350 2700);
DISPLAY INVISIBLE (-3350 2700);
FORCEPROP 1 LAST BODY_TYPE PLUMBING
J 0
(-3350 2750);
DISPLAY 0.872340 (-3350 2750);
PAINT GREEN (-3350 2750);
DISPLAY INVISIBLE (-3350 2750);
FORCEPROP 1 LAST HDL_TAP TRUE
J 0
(-3025 2575);
DISPLAY 0.872340 (-3025 2575);
DISPLAY INVISIBLE (-3025 2575);
FORCEPROP 1 LAST PATH I235
J 0
(-3352 2700);
DISPLAY 0.872340 (-3352 2700);
PAINT GREEN (-3352 2700);
DISPLAY INVISIBLE (-3352 2700);
FORCEADD SCONN288_DDR506112002KQ..2
(-4300 3650);
FORCEPROP 1 LAST LOCATION J29
J 0
(-4900 4975);
DISPLAY 0.468085 (-4900 4975);
PAINT SKYBLUE (-4900 4975);
FORCEPROP 0 LAST $SEC 2
J 0
(-4750 5125);
DISPLAY 0.680851 (-4750 5125);
PAINT MONO (-4750 5125);
DISPLAY INVISIBLE (-4750 5125);
FORCEPROP 0 LAST CDS_SEC 2
J 0
(-4750 5125);
DISPLAY 1.021277 (-4750 5125);
DISPLAY INVISIBLE (-4750 5125);
FORCEPROP 0 LASTPIN (-3550 3700) $PN 12
J 0
(-3540 3710);
DISPLAY 0.680851 (-3540 3710);
PAINT MONO (-3540 3710);
FORCEPROP 0 LASTPIN (-3550 3750) $PN 11
J 0
(-3540 3760);
DISPLAY 0.680851 (-3540 3760);
PAINT MONO (-3540 3760);
FORCEPROP 0 LASTPIN (-3550 2650) $PN 105
J 0
(-3540 2660);
DISPLAY 0.680851 (-3540 2660);
PAINT MONO (-3540 2660);
FORCEPROP 0 LASTPIN (-3550 2700) $PN 104
J 0
(-3540 2710);
DISPLAY 0.680851 (-3540 2710);
PAINT MONO (-3540 2710);
FORCEPROP 0 LASTPIN (-3550 3800) $PN 23
J 0
(-3540 3810);
DISPLAY 0.680851 (-3540 3810);
PAINT MONO (-3540 3810);
FORCEPROP 0 LASTPIN (-3550 3850) $PN 22
J 0
(-3540 3860);
DISPLAY 0.680851 (-3540 3860);
PAINT MONO (-3540 3860);
FORCEPROP 0 LASTPIN (-3550 2750) $PN 116
J 0
(-3540 2760);
DISPLAY 0.680851 (-3540 2760);
PAINT MONO (-3540 2760);
FORCEPROP 0 LASTPIN (-3550 2800) $PN 115
J 0
(-3540 2810);
DISPLAY 0.680851 (-3540 2810);
PAINT MONO (-3540 2810);
FORCEPROP 0 LASTPIN (-3550 3900) $PN 34
J 0
(-3540 3910);
DISPLAY 0.680851 (-3540 3910);
PAINT MONO (-3540 3910);
FORCEPROP 0 LASTPIN (-3550 3950) $PN 33
J 0
(-3540 3960);
DISPLAY 0.680851 (-3540 3960);
PAINT MONO (-3540 3960);
FORCEPROP 0 LASTPIN (-3550 2850) $PN 127
J 0
(-3540 2860);
DISPLAY 0.680851 (-3540 2860);
PAINT MONO (-3540 2860);
FORCEPROP 0 LASTPIN (-3550 2900) $PN 126
J 0
(-3540 2910);
DISPLAY 0.680851 (-3540 2910);
PAINT MONO (-3540 2910);
FORCEPROP 0 LASTPIN (-3550 4000) $PN 45
J 0
(-3540 4010);
DISPLAY 0.680851 (-3540 4010);
PAINT MONO (-3540 4010);
FORCEPROP 0 LASTPIN (-3550 4050) $PN 44
J 0
(-3540 4060);
DISPLAY 0.680851 (-3540 4060);
PAINT MONO (-3540 4060);
FORCEPROP 0 LASTPIN (-3550 2950) $PN 138
J 0
(-3540 2960);
DISPLAY 0.680851 (-3540 2960);
PAINT MONO (-3540 2960);
FORCEPROP 0 LASTPIN (-3550 3000) $PN 137
J 0
(-3540 3010);
DISPLAY 0.680851 (-3540 3010);
PAINT MONO (-3540 3010);
FORCEPROP 0 LASTPIN (-3550 4100) $PN 56
J 0
(-3540 4110);
DISPLAY 0.680851 (-3540 4110);
PAINT MONO (-3540 4110);
FORCEPROP 0 LASTPIN (-3550 4150) $PN 55
J 0
(-3540 4160);
DISPLAY 0.680851 (-3540 4160);
PAINT MONO (-3540 4160);
FORCEPROP 0 LASTPIN (-3550 3050) $PN 238
J 0
(-3540 3060);
DISPLAY 0.680851 (-3540 3060);
PAINT MONO (-3540 3060);
FORCEPROP 0 LASTPIN (-3550 3100) $PN 239
J 0
(-3540 3110);
DISPLAY 0.680851 (-3540 3110);
PAINT MONO (-3540 3110);
FORCEPROP 0 LASTPIN (-3550 4200) $PN 156
J 0
(-3540 4210);
DISPLAY 0.680851 (-3540 4210);
PAINT MONO (-3540 4210);
FORCEPROP 0 LASTPIN (-3550 4250) $PN 157
J 0
(-3540 4260);
DISPLAY 0.680851 (-3540 4260);
PAINT MONO (-3540 4260);
FORCEPROP 0 LASTPIN (-3550 3150) $PN 249
J 0
(-3540 3160);
DISPLAY 0.680851 (-3540 3160);
PAINT MONO (-3540 3160);
FORCEPROP 0 LASTPIN (-3550 3200) $PN 250
J 0
(-3540 3210);
DISPLAY 0.680851 (-3540 3210);
PAINT MONO (-3540 3210);
FORCEPROP 0 LASTPIN (-3550 4300) $PN 167
J 0
(-3540 4310);
DISPLAY 0.680851 (-3540 4310);
PAINT MONO (-3540 4310);
FORCEPROP 0 LASTPIN (-3550 4350) $PN 168
J 0
(-3540 4360);
DISPLAY 0.680851 (-3540 4360);
PAINT MONO (-3540 4360);
FORCEPROP 0 LASTPIN (-3550 3250) $PN 260
J 0
(-3540 3260);
DISPLAY 0.680851 (-3540 3260);
PAINT MONO (-3540 3260);
FORCEPROP 0 LASTPIN (-3550 3300) $PN 261
J 0
(-3540 3310);
DISPLAY 0.680851 (-3540 3310);
PAINT MONO (-3540 3310);
FORCEPROP 0 LASTPIN (-3550 4400) $PN 178
J 0
(-3540 4410);
DISPLAY 0.680851 (-3540 4410);
PAINT MONO (-3540 4410);
FORCEPROP 0 LASTPIN (-3550 4450) $PN 179
J 0
(-3540 4460);
DISPLAY 0.680851 (-3540 4460);
PAINT MONO (-3540 4460);
FORCEPROP 0 LASTPIN (-3550 3350) $PN 271
J 0
(-3540 3360);
DISPLAY 0.680851 (-3540 3360);
PAINT MONO (-3540 3360);
FORCEPROP 0 LASTPIN (-3550 3400) $PN 272
J 0
(-3540 3410);
DISPLAY 0.680851 (-3540 3410);
PAINT MONO (-3540 3410);
FORCEPROP 0 LASTPIN (-3550 4500) $PN 189
J 0
(-3540 4510);
DISPLAY 0.680851 (-3540 4510);
PAINT MONO (-3540 4510);
FORCEPROP 0 LASTPIN (-3550 4550) $PN 190
J 0
(-3540 4560);
DISPLAY 0.680851 (-3540 4560);
PAINT MONO (-3540 4560);
FORCEPROP 0 LASTPIN (-3550 3450) $PN 282
J 0
(-3540 3460);
DISPLAY 0.680851 (-3540 3460);
PAINT MONO (-3540 3460);
FORCEPROP 0 LASTPIN (-3550 3500) $PN 283
J 0
(-3540 3510);
DISPLAY 0.680851 (-3540 3510);
PAINT MONO (-3540 3510);
FORCEPROP 0 LASTPIN (-3550 4600) $PN 200
J 0
(-3540 4610);
DISPLAY 0.680851 (-3540 4610);
PAINT MONO (-3540 4610);
FORCEPROP 0 LASTPIN (-3550 4650) $PN 201
J 0
(-3540 4660);
DISPLAY 0.680851 (-3540 4660);
PAINT MONO (-3540 4660);
FORCEPROP 0 LASTPIN (-3550 3550) $PN 94
J 0
(-3540 3560);
DISPLAY 0.680851 (-3540 3560);
PAINT MONO (-3540 3560);
FORCEPROP 0 LASTPIN (-3550 3600) $PN 93
J 0
(-3540 3610);
DISPLAY 0.680851 (-3540 3610);
PAINT MONO (-3540 3610);
FORCEPROP 2 LAST VALUE SCONN288_DDR506112002KQ
J 0
(-4750 5025);
DISPLAY 0.489362 (-4750 5025);
PAINT SKYBLUE (-4750 5025);
FORCEPROP 2 LAST PART_TYPE SMLF
J 0
(-4750 5075);
DISPLAY 1.021277 (-4750 5075);
FORCEPROP 1 LAST MATERIAL IO
J 0
(-4900 4825);
DISPLAY 0.468085 (-4900 4825);
PAINT SKYBLUE (-4900 4825);
FORCEPROP 1 LAST PART_NUMBER DFHST8FS479
J 0
(-4900 4900);
DISPLAY 0.468085 (-4900 4900);
PAINT SKYBLUE (-4900 4900);
FORCEPROP 1 LAST CDS_LMAN_SYM_OUTLINE -600,1150,600,-1150
J 0
(-4300 3650);
DISPLAY 0.468085 (-4300 3650);
PAINT GREEN (-4300 3650);
DISPLAY INVISIBLE (-4300 3650);
FORCEPROP 1 LAST PATH I236
J 0
(-4300 3650);
DISPLAY 0.723404 (-4300 3650);
PAINT GREEN (-4300 3650);
DISPLAY INVISIBLE (-4300 3650);
FORCEPROP 1 LAST NEEDS_NO_SIZE TRUE
J 0
(-4300 3650);
DISPLAY 0.723404 (-4300 3650);
PAINT GREEN (-4300 3650);
DISPLAY INVISIBLE (-4300 3650);
FORCEPROP 2 LAST CDS_LIB pure_quanta
J 0
(-4300 3650);
DISPLAY INVISIBLE (-4300 3650);
FORCEADD GND..1
(-2725 5425);
FORCEPROP 3 LASTPIN (-2725 5475) SIG_NAME GND\g
J 0
(-2715 5485);
DISPLAY 0.659574 (-2715 5485);
PAINT MONO (-2715 5485);
DISPLAY INVISIBLE (-2715 5485);
FORCEPROP 2 LAST CDS_LIB pure_quanta_power
J 0
(-2725 5425);
DISPLAY INVISIBLE (-2725 5425);
FORCEPROP 2 LAST BOM_COST MEM
J 0
(-2700 5550);
DISPLAY 0.659574 (-2700 5550);
DISPLAY INVISIBLE (-2700 5550);
FORCEPROP 1 LAST SIZE 1B
J 0
(-2650 5375);
DISPLAY 0.723404 (-2650 5375);
PAINT GREEN (-2650 5375);
DISPLAY INVISIBLE (-2650 5375);
FORCEPROP 1 LAST PATH I237
J 0
(-2650 5425);
DISPLAY 0.872340 (-2650 5425);
PAINT AQUA (-2650 5425);
DISPLAY INVISIBLE (-2650 5425);
FORCEPROP 2 LAST ROOM MEM_EFGH_DECOUPLING_CAPS
J 0
(-2700 5500);
DISPLAY 0.659574 (-2700 5500);
PAINT RED (-2700 5500);
DISPLAY INVISIBLE (-2700 5500);
FORCEPROP 1 LAST HDL_POWER GND
J 0
(-2725 5575);
DISPLAY 0.723404 (-2725 5575);
PAINT GREEN (-2725 5575);
DISPLAY INVISIBLE (-2725 5575);
FORCEADD Q_CAP..1
R 2
(-2725 5775);
FORCEPROP 1 LAST LOCATION C536
J 2
(-2775 5875);
DISPLAY 0.489362 (-2775 5875);
PAINT SKYBLUE (-2775 5875);
FORCEPROP 0 LAST $SEC 1
J 0
(-2775 5925);
DISPLAY 0.680851 (-2775 5925);
PAINT MONO (-2775 5925);
DISPLAY INVISIBLE (-2775 5925);
FORCEPROP 0 LAST CDS_SEC 1
J 0
(-2775 5925);
DISPLAY 0.680851 (-2775 5925);
DISPLAY INVISIBLE (-2775 5925);
FORCEPROP 1 LASTPIN (-2725 5875) $PN 1
J 2
(-2735 5855);
DISPLAY 0.489362 (-2735 5855);
PAINT MONO (-2735 5855);
FORCEPROP 1 LASTPIN (-2725 5675) $PN 2
J 2
(-2735 5655);
DISPLAY 0.489362 (-2735 5655);
PAINT MONO (-2735 5655);
FORCEPROP 1 LAST MATERIAL X6S
J 2
(-2775 5675);
DISPLAY 0.489362 (-2775 5675);
PAINT SKYBLUE (-2775 5675);
FORCEPROP 1 LAST TOLERANCE 10%
J 2
(-2775 5725);
DISPLAY 0.489362 (-2775 5725);
PAINT SKYBLUE (-2775 5725);
FORCEPROP 1 LAST VALUE 10UF
J 2
(-2775 5825);
DISPLAY 0.489362 (-2775 5825);
PAINT SKYBLUE (-2775 5825);
FORCEPROP 1 LAST PART_NUMBER CH6104KEA00
J 2
(-2775 5625);
DISPLAY 0.489362 (-2775 5625);
PAINT SKYBLUE (-2775 5625);
FORCEPROP 1 LAST VOLTAGE 25V
J 2
(-2775 5775);
DISPLAY 0.489362 (-2775 5775);
PAINT SKYBLUE (-2775 5775);
FORCEPROP 1 LAST PACK_TYPE C0805
J 2
(-2775 5575);
DISPLAY 0.489362 (-2775 5575);
PAINT SKYBLUE (-2775 5575);
FORCEPROP 0 LAST BOM_COST MEM
J 2
(-2780 5920);
DISPLAY 0.595745 (-2780 5920);
PAINT MONO (-2780 5920);
DISPLAY INVISIBLE (-2780 5920);
FORCEPROP 2 LAST CDS_LIB pure_quanta
J 0
(-2725 5775);
DISPLAY INVISIBLE (-2725 5775);
FORCEPROP 1 LAST PATH I238
J 2
(-2775 5925);
DISPLAY 0.978723 (-2775 5925);
PAINT WHITE (-2775 5925);
DISPLAY INVISIBLE (-2775 5925);
FORCEPROP 0 LAST ROOM MEM_CH_A_CPU0_DIMM1
J 2
(-2780 5920);
DISPLAY 0.595745 (-2780 5920);
PAINT RED (-2780 5920);
DISPLAY INVISIBLE (-2780 5920);
FORCEADD Q_CAP..1
R 2
(-2150 5775);
FORCEPROP 1 LAST LOCATION C537
J 2
(-2200 5875);
DISPLAY 0.489362 (-2200 5875);
PAINT SKYBLUE (-2200 5875);
FORCEPROP 0 LAST $SEC 1
J 0
(-2200 5925);
DISPLAY 0.680851 (-2200 5925);
PAINT MONO (-2200 5925);
DISPLAY INVISIBLE (-2200 5925);
FORCEPROP 0 LAST CDS_SEC 1
J 0
(-2200 5925);
DISPLAY 0.680851 (-2200 5925);
DISPLAY INVISIBLE (-2200 5925);
FORCEPROP 1 LASTPIN (-2150 5875) $PN 1
J 2
(-2160 5855);
DISPLAY 0.489362 (-2160 5855);
PAINT MONO (-2160 5855);
FORCEPROP 1 LASTPIN (-2150 5675) $PN 2
J 2
(-2160 5655);
DISPLAY 0.489362 (-2160 5655);
PAINT MONO (-2160 5655);
FORCEPROP 1 LAST MATERIAL X6S
J 2
(-2200 5675);
DISPLAY 0.489362 (-2200 5675);
PAINT SKYBLUE (-2200 5675);
FORCEPROP 1 LAST TOLERANCE 10%
J 2
(-2200 5725);
DISPLAY 0.489362 (-2200 5725);
PAINT SKYBLUE (-2200 5725);
FORCEPROP 1 LAST VALUE 10UF
J 2
(-2200 5825);
DISPLAY 0.489362 (-2200 5825);
PAINT SKYBLUE (-2200 5825);
FORCEPROP 1 LAST PART_NUMBER CH6104KEA00
J 2
(-2200 5625);
DISPLAY 0.489362 (-2200 5625);
PAINT SKYBLUE (-2200 5625);
FORCEPROP 1 LAST VOLTAGE 25V
J 2
(-2200 5775);
DISPLAY 0.489362 (-2200 5775);
PAINT SKYBLUE (-2200 5775);
FORCEPROP 1 LAST PACK_TYPE C0805
J 2
(-2200 5575);
DISPLAY 0.489362 (-2200 5575);
PAINT SKYBLUE (-2200 5575);
FORCEPROP 0 LAST BOM_COST MEM
J 2
(-2205 5920);
DISPLAY 0.595745 (-2205 5920);
PAINT MONO (-2205 5920);
DISPLAY INVISIBLE (-2205 5920);
FORCEPROP 2 LAST CDS_LIB pure_quanta
J 0
(-2150 5775);
DISPLAY INVISIBLE (-2150 5775);
FORCEPROP 1 LAST PATH I239
J 2
(-2200 5925);
DISPLAY 0.978723 (-2200 5925);
PAINT WHITE (-2200 5925);
DISPLAY INVISIBLE (-2200 5925);
FORCEPROP 0 LAST ROOM MEM_CH_A_CPU0_DIMM1
J 2
(-2205 5920);
DISPLAY 0.595745 (-2205 5920);
PAINT RED (-2205 5920);
DISPLAY INVISIBLE (-2205 5920);
FORCEADD TAP..1
R 2
(-7550 3175);
FORCEPROP 3 LASTPIN (-7500 3175) SIG_NAME M_J_CPU1_SB_CB<1>
J 0
(-7490 3185);
DISPLAY 0.659574 (-7490 3185);
PAINT MONO (-7490 3185);
DISPLAY INVISIBLE (-7490 3185);
FORCEPROP 1 LASTPIN (-7500 3175) BN 1
J 2
(-7488 3183);
DISPLAY 0.489362 (-7488 3183);
PAINT GREEN (-7488 3183);
FORCEPROP 2 LAST CDS_LIB mstr_standard
J 0
(-7550 3175);
DISPLAY 0.723404 (-7550 3175);
PAINT MONO (-7550 3175);
DISPLAY INVISIBLE (-7550 3175);
FORCEPROP 1 LAST BODY_TYPE PLUMBING
J 2
(-7550 3225);
DISPLAY 0.872340 (-7550 3225);
PAINT GREEN (-7550 3225);
DISPLAY INVISIBLE (-7550 3225);
FORCEPROP 1 LAST HDL_TAP TRUE
J 2
(-7875 3050);
DISPLAY 0.872340 (-7875 3050);
DISPLAY INVISIBLE (-7875 3050);
FORCEPROP 1 LAST PATH I24
J 2
(-7548 3175);
DISPLAY 0.872340 (-7548 3175);
PAINT GREEN (-7548 3175);
DISPLAY INVISIBLE (-7548 3175);
FORCEADD UNIVERSAL_POWER..1
(-2725 6100);
FORCEPROP 3 LASTPIN (-2725 6050) SIG_NAME P12V_MEM_1\g
J 0
(-2715 6060);
DISPLAY 0.659574 (-2715 6060);
PAINT MONO (-2715 6060);
DISPLAY INVISIBLE (-2715 6060);
FORCEPROP 1 LAST HDL_POWER P12V_MEM_1
J 1
(-2725 6150);
DISPLAY 0.489362 (-2725 6150);
PAINT GREEN (-2725 6150);
FORCEPROP 2 LAST CDS_LIB pure_quanta_power
J 0
(-2725 6100);
DISPLAY INVISIBLE (-2725 6100);
FORCEPROP 1 LAST PATH I240
J 0
(-2675 6125);
DISPLAY 0.872340 (-2675 6125);
PAINT AQUA (-2675 6125);
DISPLAY INVISIBLE (-2675 6125);
FORCEADD OFFPAGE..1
(-8175 2625);
FORCEPROP 2 LAST $XR5 108 
J 0
(-9027 2625);
DISPLAY 0.638298 (-9027 2625);
PAINT MONO (-9027 2625);
FORCEPROP 2 LAST $XR4 107 
J 0
(-8907 2625);
DISPLAY 0.638298 (-8907 2625);
PAINT MONO (-8907 2625);
FORCEPROP 2 LAST $XR3 105 
J 0
(-8787 2625);
DISPLAY 0.638298 (-8787 2625);
PAINT MONO (-8787 2625);
FORCEPROP 2 LAST $XR2 104 
J 0
(-8667 2625);
DISPLAY 0.638298 (-8667 2625);
PAINT MONO (-8667 2625);
FORCEPROP 2 LAST $XR1 103 
J 0
(-8547 2625);
DISPLAY 0.638298 (-8547 2625);
PAINT MONO (-8547 2625);
FORCEPROP 2 LAST $XR0 136 
J 0
(-8427 2625);
DISPLAY 0.638298 (-8427 2625);
PAINT MONO (-8427 2625);
FORCEPROP 2 LAST PATH I241
J 0
(-8450 2675);
DISPLAY 0.680851 (-8450 2675);
DISPLAY INVISIBLE (-8450 2675);
FORCEPROP 1 LAST COMMENT_BODY TRUE
J 0
(-8050 2525);
DISPLAY 0.872340 (-8050 2525);
PAINT GREEN (-8050 2525);
DISPLAY INVISIBLE (-8050 2525);
FORCEPROP 1 LAST OFFPAGE TRUE
J 0
(-7850 2500);
DISPLAY 0.872340 (-7850 2500);
PAINT GREEN (-7850 2500);
DISPLAY INVISIBLE (-7850 2500);
FORCEPROP 2 LAST CDS_LIB mstr_standard
J 0
(-8175 2625);
DISPLAY 0.808511 (-8175 2625);
DISPLAY INVISIBLE (-8175 2625);
FORCEADD Q_RES..1
(-7600 2625);
FORCEPROP 1 LAST $LOCATION R1589
J 0
(-7650 2650);
DISPLAY 0.510638 (-7650 2650);
PAINT SKYBLUE (-7650 2650);
FORCEPROP 0 LAST CDS_LOCATION R1589
J 0
(-7650 2725);
DISPLAY 0.680851 (-7650 2725);
DISPLAY INVISIBLE (-7650 2725);
FORCEPROP 0 LAST $SEC 1
J 0
(-7650 2725);
DISPLAY 0.680851 (-7650 2725);
PAINT MONO (-7650 2725);
DISPLAY INVISIBLE (-7650 2725);
FORCEPROP 0 LAST CDS_SEC 1
J 0
(-7650 2725);
DISPLAY 0.680851 (-7650 2725);
DISPLAY INVISIBLE (-7650 2725);
FORCEPROP 1 LASTPIN (-7700 2625) $PN 1
J 0
(-7688 2637);
DISPLAY 0.787234 (-7688 2637);
PAINT MONO (-7688 2637);
FORCEPROP 1 LASTPIN (-7500 2625) $PN 2
J 0
(-7538 2637);
DISPLAY 0.787234 (-7538 2637);
PAINT MONO (-7538 2637);
FORCEPROP 1 LAST VALUE 49.9
J 2
(-7450 2675);
DISPLAY 0.510638 (-7450 2675);
PAINT SKYBLUE (-7450 2675);
FORCEPROP 2 LAST CDS_LIB pure_quanta
J 0
(-7600 2625);
DISPLAY INVISIBLE (-7600 2625);
FORCEPROP 1 LAST PATH I242
J 0
(-7650 2775);
DISPLAY 0.978723 (-7650 2775);
PAINT WHITE (-7650 2775);
DISPLAY INVISIBLE (-7650 2775);
FORCEPROP 1 LAST MATERIAL CHIP
J 0
(-7600 2475);
DISPLAY 0.978723 (-7600 2475);
DISPLAY INVISIBLE (-7600 2475);
FORCEPROP 1 LAST PACK_TYPE 0402LF
J 0
(-7350 2475);
DISPLAY 0.978723 (-7350 2475);
DISPLAY INVISIBLE (-7350 2475);
FORCEPROP 1 LAST WATTAGE 1/16W
J 2
(-7625 2475);
DISPLAY 0.978723 (-7625 2475);
DISPLAY INVISIBLE (-7625 2475);
FORCEPROP 1 LAST TOLERANCE 1%
J 0
(-7600 2525);
DISPLAY 0.978723 (-7600 2525);
DISPLAY INVISIBLE (-7600 2525);
FORCEPROP 1 LAST PART_NUMBER CS04992FB07
J 0
(-7650 2725);
DISPLAY 0.978723 (-7650 2725);
DISPLAY INVISIBLE (-7650 2725);
FORCEADD TAP..1
R 2
(-7550 3225);
FORCEPROP 3 LASTPIN (-7500 3225) SIG_NAME M_J_CPU1_SB_CB<2>
J 0
(-7490 3235);
DISPLAY 0.659574 (-7490 3235);
PAINT MONO (-7490 3235);
DISPLAY INVISIBLE (-7490 3235);
FORCEPROP 1 LASTPIN (-7500 3225) BN 2
J 2
(-7488 3233);
DISPLAY 0.489362 (-7488 3233);
PAINT GREEN (-7488 3233);
FORCEPROP 2 LAST CDS_LIB mstr_standard
J 0
(-7550 3225);
DISPLAY 0.723404 (-7550 3225);
PAINT MONO (-7550 3225);
DISPLAY INVISIBLE (-7550 3225);
FORCEPROP 1 LAST BODY_TYPE PLUMBING
J 2
(-7550 3275);
DISPLAY 0.872340 (-7550 3275);
PAINT GREEN (-7550 3275);
DISPLAY INVISIBLE (-7550 3275);
FORCEPROP 1 LAST HDL_TAP TRUE
J 2
(-7875 3100);
DISPLAY 0.872340 (-7875 3100);
DISPLAY INVISIBLE (-7875 3100);
FORCEPROP 1 LAST PATH I25
J 2
(-7548 3225);
DISPLAY 0.872340 (-7548 3225);
PAINT GREEN (-7548 3225);
DISPLAY INVISIBLE (-7548 3225);
FORCEADD TAP..1
R 2
(-7550 3325);
FORCEPROP 3 LASTPIN (-7500 3325) SIG_NAME M_J_CPU1_SB_CB<4>
J 0
(-7490 3335);
DISPLAY 0.659574 (-7490 3335);
PAINT MONO (-7490 3335);
DISPLAY INVISIBLE (-7490 3335);
FORCEPROP 1 LASTPIN (-7500 3325) BN 4
J 2
(-7488 3333);
DISPLAY 0.489362 (-7488 3333);
PAINT GREEN (-7488 3333);
FORCEPROP 2 LAST CDS_LIB mstr_standard
J 0
(-7550 3325);
DISPLAY 0.723404 (-7550 3325);
PAINT MONO (-7550 3325);
DISPLAY INVISIBLE (-7550 3325);
FORCEPROP 1 LAST BODY_TYPE PLUMBING
J 2
(-7550 3375);
DISPLAY 0.872340 (-7550 3375);
PAINT GREEN (-7550 3375);
DISPLAY INVISIBLE (-7550 3375);
FORCEPROP 1 LAST HDL_TAP TRUE
J 2
(-7875 3200);
DISPLAY 0.872340 (-7875 3200);
DISPLAY INVISIBLE (-7875 3200);
FORCEPROP 1 LAST PATH I26
J 2
(-7548 3325);
DISPLAY 0.872340 (-7548 3325);
PAINT GREEN (-7548 3325);
DISPLAY INVISIBLE (-7548 3325);
FORCEADD TAP..1
R 2
(-7550 3275);
FORCEPROP 3 LASTPIN (-7500 3275) SIG_NAME M_J_CPU1_SB_CB<3>
J 0
(-7490 3285);
DISPLAY 0.659574 (-7490 3285);
PAINT MONO (-7490 3285);
DISPLAY INVISIBLE (-7490 3285);
FORCEPROP 1 LASTPIN (-7500 3275) BN 3
J 2
(-7488 3283);
DISPLAY 0.489362 (-7488 3283);
PAINT GREEN (-7488 3283);
FORCEPROP 2 LAST CDS_LIB mstr_standard
J 0
(-7550 3275);
DISPLAY 0.723404 (-7550 3275);
PAINT MONO (-7550 3275);
DISPLAY INVISIBLE (-7550 3275);
FORCEPROP 1 LAST BODY_TYPE PLUMBING
J 2
(-7550 3325);
DISPLAY 0.872340 (-7550 3325);
PAINT GREEN (-7550 3325);
DISPLAY INVISIBLE (-7550 3325);
FORCEPROP 1 LAST HDL_TAP TRUE
J 2
(-7875 3150);
DISPLAY 0.872340 (-7875 3150);
DISPLAY INVISIBLE (-7875 3150);
FORCEPROP 1 LAST PATH I27
J 2
(-7548 3275);
DISPLAY 0.872340 (-7548 3275);
PAINT GREEN (-7548 3275);
DISPLAY INVISIBLE (-7548 3275);
FORCEADD TAP..1
R 2
(-7550 3375);
FORCEPROP 3 LASTPIN (-7500 3375) SIG_NAME M_J_CPU1_SB_CB<5>
J 0
(-7490 3385);
DISPLAY 0.659574 (-7490 3385);
PAINT MONO (-7490 3385);
DISPLAY INVISIBLE (-7490 3385);
FORCEPROP 1 LASTPIN (-7500 3375) BN 5
J 2
(-7488 3383);
DISPLAY 0.489362 (-7488 3383);
PAINT GREEN (-7488 3383);
FORCEPROP 2 LAST CDS_LIB mstr_standard
J 0
(-7550 3375);
DISPLAY 0.723404 (-7550 3375);
PAINT MONO (-7550 3375);
DISPLAY INVISIBLE (-7550 3375);
FORCEPROP 1 LAST BODY_TYPE PLUMBING
J 2
(-7550 3425);
DISPLAY 0.872340 (-7550 3425);
PAINT GREEN (-7550 3425);
DISPLAY INVISIBLE (-7550 3425);
FORCEPROP 1 LAST HDL_TAP TRUE
J 2
(-7875 3250);
DISPLAY 0.872340 (-7875 3250);
DISPLAY INVISIBLE (-7875 3250);
FORCEPROP 1 LAST PATH I28
J 2
(-7548 3375);
DISPLAY 0.872340 (-7548 3375);
PAINT GREEN (-7548 3375);
DISPLAY INVISIBLE (-7548 3375);
FORCEADD TAP..1
R 2
(-7550 3425);
FORCEPROP 3 LASTPIN (-7500 3425) SIG_NAME M_J_CPU1_SB_CB<6>
J 0
(-7490 3435);
DISPLAY 0.659574 (-7490 3435);
PAINT MONO (-7490 3435);
DISPLAY INVISIBLE (-7490 3435);
FORCEPROP 1 LASTPIN (-7500 3425) BN 6
J 2
(-7488 3433);
DISPLAY 0.489362 (-7488 3433);
PAINT GREEN (-7488 3433);
FORCEPROP 2 LAST CDS_LIB mstr_standard
J 0
(-7550 3425);
DISPLAY 0.723404 (-7550 3425);
PAINT MONO (-7550 3425);
DISPLAY INVISIBLE (-7550 3425);
FORCEPROP 1 LAST BODY_TYPE PLUMBING
J 2
(-7550 3475);
DISPLAY 0.872340 (-7550 3475);
PAINT GREEN (-7550 3475);
DISPLAY INVISIBLE (-7550 3475);
FORCEPROP 1 LAST HDL_TAP TRUE
J 2
(-7875 3300);
DISPLAY 0.872340 (-7875 3300);
DISPLAY INVISIBLE (-7875 3300);
FORCEPROP 1 LAST PATH I29
J 2
(-7548 3425);
DISPLAY 0.872340 (-7548 3425);
PAINT GREEN (-7548 3425);
DISPLAY INVISIBLE (-7548 3425);
FORCEADD TAP..1
R 2
(-7550 3475);
FORCEPROP 3 LASTPIN (-7500 3475) SIG_NAME M_J_CPU1_SB_CB<7>
J 0
(-7490 3485);
DISPLAY 0.659574 (-7490 3485);
PAINT MONO (-7490 3485);
DISPLAY INVISIBLE (-7490 3485);
FORCEPROP 1 LASTPIN (-7500 3475) BN 7
J 2
(-7488 3483);
DISPLAY 0.489362 (-7488 3483);
PAINT GREEN (-7488 3483);
FORCEPROP 2 LAST CDS_LIB mstr_standard
J 0
(-7550 3475);
DISPLAY 0.723404 (-7550 3475);
PAINT MONO (-7550 3475);
DISPLAY INVISIBLE (-7550 3475);
FORCEPROP 1 LAST BODY_TYPE PLUMBING
J 2
(-7550 3525);
DISPLAY 0.872340 (-7550 3525);
PAINT GREEN (-7550 3525);
DISPLAY INVISIBLE (-7550 3525);
FORCEPROP 1 LAST HDL_TAP TRUE
J 2
(-7875 3350);
DISPLAY 0.872340 (-7875 3350);
DISPLAY INVISIBLE (-7875 3350);
FORCEPROP 1 LAST PATH I30
J 2
(-7548 3475);
DISPLAY 0.872340 (-7548 3475);
PAINT GREEN (-7548 3475);
DISPLAY INVISIBLE (-7548 3475);
FORCEADD TAP..1
R 2
(-7550 3575);
FORCEPROP 3 LASTPIN (-7500 3575) SIG_NAME M_J_CPU1_SA_CB<0>
J 0
(-7490 3585);
DISPLAY 0.659574 (-7490 3585);
PAINT MONO (-7490 3585);
DISPLAY INVISIBLE (-7490 3585);
FORCEPROP 1 LASTPIN (-7500 3575) BN 0
J 2
(-7488 3583);
DISPLAY 0.489362 (-7488 3583);
PAINT GREEN (-7488 3583);
FORCEPROP 2 LAST CDS_LIB mstr_standard
J 0
(-7550 3575);
DISPLAY 0.723404 (-7550 3575);
PAINT MONO (-7550 3575);
DISPLAY INVISIBLE (-7550 3575);
FORCEPROP 1 LAST BODY_TYPE PLUMBING
J 2
(-7550 3625);
DISPLAY 0.872340 (-7550 3625);
PAINT GREEN (-7550 3625);
DISPLAY INVISIBLE (-7550 3625);
FORCEPROP 1 LAST HDL_TAP TRUE
J 2
(-7875 3450);
DISPLAY 0.872340 (-7875 3450);
DISPLAY INVISIBLE (-7875 3450);
FORCEPROP 1 LAST PATH I31
J 2
(-7548 3575);
DISPLAY 0.872340 (-7548 3575);
PAINT GREEN (-7548 3575);
DISPLAY INVISIBLE (-7548 3575);
FORCEADD TAP..1
R 2
(-7550 3625);
FORCEPROP 3 LASTPIN (-7500 3625) SIG_NAME M_J_CPU1_SA_CB<1>
J 0
(-7490 3635);
DISPLAY 0.659574 (-7490 3635);
PAINT MONO (-7490 3635);
DISPLAY INVISIBLE (-7490 3635);
FORCEPROP 1 LASTPIN (-7500 3625) BN 1
J 2
(-7488 3633);
DISPLAY 0.489362 (-7488 3633);
PAINT GREEN (-7488 3633);
FORCEPROP 2 LAST CDS_LIB mstr_standard
J 0
(-7550 3625);
DISPLAY 0.723404 (-7550 3625);
PAINT MONO (-7550 3625);
DISPLAY INVISIBLE (-7550 3625);
FORCEPROP 1 LAST BODY_TYPE PLUMBING
J 2
(-7550 3675);
DISPLAY 0.872340 (-7550 3675);
PAINT GREEN (-7550 3675);
DISPLAY INVISIBLE (-7550 3675);
FORCEPROP 1 LAST HDL_TAP TRUE
J 2
(-7875 3500);
DISPLAY 0.872340 (-7875 3500);
DISPLAY INVISIBLE (-7875 3500);
FORCEPROP 1 LAST PATH I32
J 2
(-7548 3625);
DISPLAY 0.872340 (-7548 3625);
PAINT GREEN (-7548 3625);
DISPLAY INVISIBLE (-7548 3625);
FORCEADD TAP..1
R 2
(-7550 3675);
FORCEPROP 3 LASTPIN (-7500 3675) SIG_NAME M_J_CPU1_SA_CB<2>
J 0
(-7490 3685);
DISPLAY 0.659574 (-7490 3685);
PAINT MONO (-7490 3685);
DISPLAY INVISIBLE (-7490 3685);
FORCEPROP 1 LASTPIN (-7500 3675) BN 2
J 2
(-7488 3683);
DISPLAY 0.489362 (-7488 3683);
PAINT GREEN (-7488 3683);
FORCEPROP 2 LAST CDS_LIB mstr_standard
J 0
(-7550 3675);
DISPLAY 0.723404 (-7550 3675);
PAINT MONO (-7550 3675);
DISPLAY INVISIBLE (-7550 3675);
FORCEPROP 1 LAST BODY_TYPE PLUMBING
J 2
(-7550 3725);
DISPLAY 0.872340 (-7550 3725);
PAINT GREEN (-7550 3725);
DISPLAY INVISIBLE (-7550 3725);
FORCEPROP 1 LAST HDL_TAP TRUE
J 2
(-7875 3550);
DISPLAY 0.872340 (-7875 3550);
DISPLAY INVISIBLE (-7875 3550);
FORCEPROP 1 LAST PATH I33
J 2
(-7548 3675);
DISPLAY 0.872340 (-7548 3675);
PAINT GREEN (-7548 3675);
DISPLAY INVISIBLE (-7548 3675);
FORCEADD TAP..1
R 2
(-7550 3725);
FORCEPROP 3 LASTPIN (-7500 3725) SIG_NAME M_J_CPU1_SA_CB<3>
J 0
(-7490 3735);
DISPLAY 0.659574 (-7490 3735);
PAINT MONO (-7490 3735);
DISPLAY INVISIBLE (-7490 3735);
FORCEPROP 1 LASTPIN (-7500 3725) BN 3
J 2
(-7488 3733);
DISPLAY 0.489362 (-7488 3733);
PAINT GREEN (-7488 3733);
FORCEPROP 2 LAST CDS_LIB mstr_standard
J 0
(-7550 3725);
DISPLAY 0.723404 (-7550 3725);
PAINT MONO (-7550 3725);
DISPLAY INVISIBLE (-7550 3725);
FORCEPROP 1 LAST BODY_TYPE PLUMBING
J 2
(-7550 3775);
DISPLAY 0.872340 (-7550 3775);
PAINT GREEN (-7550 3775);
DISPLAY INVISIBLE (-7550 3775);
FORCEPROP 1 LAST HDL_TAP TRUE
J 2
(-7875 3600);
DISPLAY 0.872340 (-7875 3600);
DISPLAY INVISIBLE (-7875 3600);
FORCEPROP 1 LAST PATH I34
J 2
(-7548 3725);
DISPLAY 0.872340 (-7548 3725);
PAINT GREEN (-7548 3725);
DISPLAY INVISIBLE (-7548 3725);
FORCEADD TAP..1
R 2
(-7550 3825);
FORCEPROP 3 LASTPIN (-7500 3825) SIG_NAME M_J_CPU1_SA_CB<5>
J 0
(-7490 3835);
DISPLAY 0.659574 (-7490 3835);
PAINT MONO (-7490 3835);
DISPLAY INVISIBLE (-7490 3835);
FORCEPROP 1 LASTPIN (-7500 3825) BN 5
J 2
(-7488 3833);
DISPLAY 0.489362 (-7488 3833);
PAINT GREEN (-7488 3833);
FORCEPROP 2 LAST CDS_LIB mstr_standard
J 0
(-7550 3825);
DISPLAY 0.723404 (-7550 3825);
PAINT MONO (-7550 3825);
DISPLAY INVISIBLE (-7550 3825);
FORCEPROP 1 LAST BODY_TYPE PLUMBING
J 2
(-7550 3875);
DISPLAY 0.872340 (-7550 3875);
PAINT GREEN (-7550 3875);
DISPLAY INVISIBLE (-7550 3875);
FORCEPROP 1 LAST HDL_TAP TRUE
J 2
(-7875 3700);
DISPLAY 0.872340 (-7875 3700);
DISPLAY INVISIBLE (-7875 3700);
FORCEPROP 1 LAST PATH I35
J 2
(-7548 3825);
DISPLAY 0.872340 (-7548 3825);
PAINT GREEN (-7548 3825);
DISPLAY INVISIBLE (-7548 3825);
FORCEADD TAP..1
R 2
(-7550 3775);
FORCEPROP 3 LASTPIN (-7500 3775) SIG_NAME M_J_CPU1_SA_CB<4>
J 0
(-7490 3785);
DISPLAY 0.659574 (-7490 3785);
PAINT MONO (-7490 3785);
DISPLAY INVISIBLE (-7490 3785);
FORCEPROP 1 LASTPIN (-7500 3775) BN 4
J 2
(-7488 3783);
DISPLAY 0.489362 (-7488 3783);
PAINT GREEN (-7488 3783);
FORCEPROP 2 LAST CDS_LIB mstr_standard
J 0
(-7550 3775);
DISPLAY 0.723404 (-7550 3775);
PAINT MONO (-7550 3775);
DISPLAY INVISIBLE (-7550 3775);
FORCEPROP 1 LAST BODY_TYPE PLUMBING
J 2
(-7550 3825);
DISPLAY 0.872340 (-7550 3825);
PAINT GREEN (-7550 3825);
DISPLAY INVISIBLE (-7550 3825);
FORCEPROP 1 LAST HDL_TAP TRUE
J 2
(-7875 3650);
DISPLAY 0.872340 (-7875 3650);
DISPLAY INVISIBLE (-7875 3650);
FORCEPROP 1 LAST PATH I36
J 2
(-7548 3775);
DISPLAY 0.872340 (-7548 3775);
PAINT GREEN (-7548 3775);
DISPLAY INVISIBLE (-7548 3775);
FORCEADD TAP..1
(-5850 2125);
FORCEPROP 3 LASTPIN (-5900 2125) SIG_NAME M_J_CPU1_SB_DQ<0>
J 0
(-5890 2135);
DISPLAY 0.659574 (-5890 2135);
PAINT MONO (-5890 2135);
DISPLAY INVISIBLE (-5890 2135);
FORCEPROP 1 LASTPIN (-5900 2125) BN 0
J 0
(-5912 2133);
DISPLAY 0.489362 (-5912 2133);
PAINT GREEN (-5912 2133);
FORCEPROP 2 LAST CDS_LIB mstr_standard
J 0
(-5850 2125);
DISPLAY 0.723404 (-5850 2125);
PAINT MONO (-5850 2125);
DISPLAY INVISIBLE (-5850 2125);
FORCEPROP 1 LAST BODY_TYPE PLUMBING
J 0
(-5850 2175);
DISPLAY 0.872340 (-5850 2175);
PAINT GREEN (-5850 2175);
DISPLAY INVISIBLE (-5850 2175);
FORCEPROP 1 LAST HDL_TAP TRUE
J 0
(-5525 2000);
DISPLAY 0.872340 (-5525 2000);
DISPLAY INVISIBLE (-5525 2000);
FORCEPROP 1 LAST PATH I37
J 0
(-5852 2125);
DISPLAY 0.872340 (-5852 2125);
PAINT GREEN (-5852 2125);
DISPLAY INVISIBLE (-5852 2125);
FORCEADD TAP..1
(-5850 2175);
FORCEPROP 3 LASTPIN (-5900 2175) SIG_NAME M_J_CPU1_SB_DQ<1>
J 0
(-5890 2185);
DISPLAY 0.659574 (-5890 2185);
PAINT MONO (-5890 2185);
DISPLAY INVISIBLE (-5890 2185);
FORCEPROP 1 LASTPIN (-5900 2175) BN 1
J 0
(-5912 2183);
DISPLAY 0.489362 (-5912 2183);
PAINT GREEN (-5912 2183);
FORCEPROP 2 LAST CDS_LIB mstr_standard
J 0
(-5850 2175);
DISPLAY 0.723404 (-5850 2175);
PAINT MONO (-5850 2175);
DISPLAY INVISIBLE (-5850 2175);
FORCEPROP 1 LAST BODY_TYPE PLUMBING
J 0
(-5850 2225);
DISPLAY 0.872340 (-5850 2225);
PAINT GREEN (-5850 2225);
DISPLAY INVISIBLE (-5850 2225);
FORCEPROP 1 LAST HDL_TAP TRUE
J 0
(-5525 2050);
DISPLAY 0.872340 (-5525 2050);
DISPLAY INVISIBLE (-5525 2050);
FORCEPROP 1 LAST PATH I38
J 0
(-5852 2175);
DISPLAY 0.872340 (-5852 2175);
PAINT GREEN (-5852 2175);
DISPLAY INVISIBLE (-5852 2175);
FORCEADD TAP..1
(-5850 2225);
FORCEPROP 3 LASTPIN (-5900 2225) SIG_NAME M_J_CPU1_SB_DQ<2>
J 0
(-5890 2235);
DISPLAY 0.659574 (-5890 2235);
PAINT MONO (-5890 2235);
DISPLAY INVISIBLE (-5890 2235);
FORCEPROP 1 LASTPIN (-5900 2225) BN 2
J 0
(-5912 2233);
DISPLAY 0.489362 (-5912 2233);
PAINT GREEN (-5912 2233);
FORCEPROP 2 LAST CDS_LIB mstr_standard
J 0
(-5850 2225);
DISPLAY 0.723404 (-5850 2225);
PAINT MONO (-5850 2225);
DISPLAY INVISIBLE (-5850 2225);
FORCEPROP 1 LAST BODY_TYPE PLUMBING
J 0
(-5850 2275);
DISPLAY 0.872340 (-5850 2275);
PAINT GREEN (-5850 2275);
DISPLAY INVISIBLE (-5850 2275);
FORCEPROP 1 LAST HDL_TAP TRUE
J 0
(-5525 2100);
DISPLAY 0.872340 (-5525 2100);
DISPLAY INVISIBLE (-5525 2100);
FORCEPROP 1 LAST PATH I39
J 0
(-5852 2225);
DISPLAY 0.872340 (-5852 2225);
PAINT GREEN (-5852 2225);
DISPLAY INVISIBLE (-5852 2225);
FORCEADD OFFPAGE..1
(-8150 2825);
FORCEPROP 2 LAST $XR0 106 
J 0
(-8432 2825);
DISPLAY 0.638298 (-8432 2825);
PAINT MONO (-8432 2825);
FORCEPROP 2 LAST PATH I4
J 0
(-8400 2875);
DISPLAY 1.021277 (-8400 2875);
DISPLAY INVISIBLE (-8400 2875);
FORCEPROP 1 LAST COMMENT_BODY TRUE
J 0
(-8025 2725);
DISPLAY 0.872340 (-8025 2725);
PAINT GREEN (-8025 2725);
DISPLAY INVISIBLE (-8025 2725);
FORCEPROP 1 LAST OFFPAGE TRUE
J 0
(-7825 2700);
DISPLAY 0.872340 (-7825 2700);
PAINT GREEN (-7825 2700);
DISPLAY INVISIBLE (-7825 2700);
FORCEPROP 2 LAST CDS_LIB mstr_standard
J 0
(-8150 2825);
DISPLAY 0.808511 (-8150 2825);
DISPLAY INVISIBLE (-8150 2825);
FORCEADD TAP..1
(-5850 2275);
FORCEPROP 3 LASTPIN (-5900 2275) SIG_NAME M_J_CPU1_SB_DQ<3>
J 0
(-5890 2285);
DISPLAY 0.659574 (-5890 2285);
PAINT MONO (-5890 2285);
DISPLAY INVISIBLE (-5890 2285);
FORCEPROP 1 LASTPIN (-5900 2275) BN 3
J 0
(-5912 2283);
DISPLAY 0.489362 (-5912 2283);
PAINT GREEN (-5912 2283);
FORCEPROP 2 LAST CDS_LIB mstr_standard
J 0
(-5850 2275);
DISPLAY 0.723404 (-5850 2275);
PAINT MONO (-5850 2275);
DISPLAY INVISIBLE (-5850 2275);
FORCEPROP 1 LAST BODY_TYPE PLUMBING
J 0
(-5850 2325);
DISPLAY 0.872340 (-5850 2325);
PAINT GREEN (-5850 2325);
DISPLAY INVISIBLE (-5850 2325);
FORCEPROP 1 LAST HDL_TAP TRUE
J 0
(-5525 2150);
DISPLAY 0.872340 (-5525 2150);
DISPLAY INVISIBLE (-5525 2150);
FORCEPROP 1 LAST PATH I40
J 0
(-5852 2275);
DISPLAY 0.872340 (-5852 2275);
PAINT GREEN (-5852 2275);
DISPLAY INVISIBLE (-5852 2275);
FORCEADD TAP..1
(-5850 2325);
FORCEPROP 3 LASTPIN (-5900 2325) SIG_NAME M_J_CPU1_SB_DQ<4>
J 0
(-5890 2335);
DISPLAY 0.659574 (-5890 2335);
PAINT MONO (-5890 2335);
DISPLAY INVISIBLE (-5890 2335);
FORCEPROP 1 LASTPIN (-5900 2325) BN 4
J 0
(-5912 2333);
DISPLAY 0.489362 (-5912 2333);
PAINT GREEN (-5912 2333);
FORCEPROP 2 LAST CDS_LIB mstr_standard
J 0
(-5850 2325);
DISPLAY 0.723404 (-5850 2325);
PAINT MONO (-5850 2325);
DISPLAY INVISIBLE (-5850 2325);
FORCEPROP 1 LAST BODY_TYPE PLUMBING
J 0
(-5850 2375);
DISPLAY 0.872340 (-5850 2375);
PAINT GREEN (-5850 2375);
DISPLAY INVISIBLE (-5850 2375);
FORCEPROP 1 LAST HDL_TAP TRUE
J 0
(-5525 2200);
DISPLAY 0.872340 (-5525 2200);
DISPLAY INVISIBLE (-5525 2200);
FORCEPROP 1 LAST PATH I41
J 0
(-5852 2325);
DISPLAY 0.872340 (-5852 2325);
PAINT GREEN (-5852 2325);
DISPLAY INVISIBLE (-5852 2325);
FORCEADD TAP..1
(-5850 2425);
FORCEPROP 3 LASTPIN (-5900 2425) SIG_NAME M_J_CPU1_SB_DQ<6>
J 0
(-5890 2435);
DISPLAY 0.659574 (-5890 2435);
PAINT MONO (-5890 2435);
DISPLAY INVISIBLE (-5890 2435);
FORCEPROP 1 LASTPIN (-5900 2425) BN 6
J 0
(-5912 2433);
DISPLAY 0.489362 (-5912 2433);
PAINT GREEN (-5912 2433);
FORCEPROP 2 LAST CDS_LIB mstr_standard
J 0
(-5850 2425);
DISPLAY 0.723404 (-5850 2425);
PAINT MONO (-5850 2425);
DISPLAY INVISIBLE (-5850 2425);
FORCEPROP 1 LAST BODY_TYPE PLUMBING
J 0
(-5850 2475);
DISPLAY 0.872340 (-5850 2475);
PAINT GREEN (-5850 2475);
DISPLAY INVISIBLE (-5850 2475);
FORCEPROP 1 LAST HDL_TAP TRUE
J 0
(-5525 2300);
DISPLAY 0.872340 (-5525 2300);
DISPLAY INVISIBLE (-5525 2300);
FORCEPROP 1 LAST PATH I42
J 0
(-5852 2425);
DISPLAY 0.872340 (-5852 2425);
PAINT GREEN (-5852 2425);
DISPLAY INVISIBLE (-5852 2425);
FORCEADD TAP..1
(-5850 2375);
FORCEPROP 3 LASTPIN (-5900 2375) SIG_NAME M_J_CPU1_SB_DQ<5>
J 0
(-5890 2385);
DISPLAY 0.659574 (-5890 2385);
PAINT MONO (-5890 2385);
DISPLAY INVISIBLE (-5890 2385);
FORCEPROP 1 LASTPIN (-5900 2375) BN 5
J 0
(-5912 2383);
DISPLAY 0.489362 (-5912 2383);
PAINT GREEN (-5912 2383);
FORCEPROP 2 LAST CDS_LIB mstr_standard
J 0
(-5850 2375);
DISPLAY 0.723404 (-5850 2375);
PAINT MONO (-5850 2375);
DISPLAY INVISIBLE (-5850 2375);
FORCEPROP 1 LAST BODY_TYPE PLUMBING
J 0
(-5850 2425);
DISPLAY 0.872340 (-5850 2425);
PAINT GREEN (-5850 2425);
DISPLAY INVISIBLE (-5850 2425);
FORCEPROP 1 LAST HDL_TAP TRUE
J 0
(-5525 2250);
DISPLAY 0.872340 (-5525 2250);
DISPLAY INVISIBLE (-5525 2250);
FORCEPROP 1 LAST PATH I43
J 0
(-5852 2375);
DISPLAY 0.872340 (-5852 2375);
PAINT GREEN (-5852 2375);
DISPLAY INVISIBLE (-5852 2375);
FORCEADD TAP..1
(-5850 2525);
FORCEPROP 3 LASTPIN (-5900 2525) SIG_NAME M_J_CPU1_SB_DQ<8>
J 0
(-5890 2535);
DISPLAY 0.659574 (-5890 2535);
PAINT MONO (-5890 2535);
DISPLAY INVISIBLE (-5890 2535);
FORCEPROP 1 LASTPIN (-5900 2525) BN 8
J 0
(-5912 2533);
DISPLAY 0.489362 (-5912 2533);
PAINT GREEN (-5912 2533);
FORCEPROP 2 LAST CDS_LIB mstr_standard
J 0
(-5850 2525);
DISPLAY 0.723404 (-5850 2525);
PAINT MONO (-5850 2525);
DISPLAY INVISIBLE (-5850 2525);
FORCEPROP 1 LAST BODY_TYPE PLUMBING
J 0
(-5850 2575);
DISPLAY 0.872340 (-5850 2575);
PAINT GREEN (-5850 2575);
DISPLAY INVISIBLE (-5850 2575);
FORCEPROP 1 LAST HDL_TAP TRUE
J 0
(-5525 2400);
DISPLAY 0.872340 (-5525 2400);
DISPLAY INVISIBLE (-5525 2400);
FORCEPROP 1 LAST PATH I44
J 0
(-5852 2525);
DISPLAY 0.872340 (-5852 2525);
PAINT GREEN (-5852 2525);
DISPLAY INVISIBLE (-5852 2525);
FORCEADD TAP..1
(-5850 2475);
FORCEPROP 3 LASTPIN (-5900 2475) SIG_NAME M_J_CPU1_SB_DQ<7>
J 0
(-5890 2485);
DISPLAY 0.659574 (-5890 2485);
PAINT MONO (-5890 2485);
DISPLAY INVISIBLE (-5890 2485);
FORCEPROP 1 LASTPIN (-5900 2475) BN 7
J 0
(-5912 2483);
DISPLAY 0.489362 (-5912 2483);
PAINT GREEN (-5912 2483);
FORCEPROP 2 LAST CDS_LIB mstr_standard
J 0
(-5850 2475);
DISPLAY 0.723404 (-5850 2475);
PAINT MONO (-5850 2475);
DISPLAY INVISIBLE (-5850 2475);
FORCEPROP 1 LAST BODY_TYPE PLUMBING
J 0
(-5850 2525);
DISPLAY 0.872340 (-5850 2525);
PAINT GREEN (-5850 2525);
DISPLAY INVISIBLE (-5850 2525);
FORCEPROP 1 LAST HDL_TAP TRUE
J 0
(-5525 2350);
DISPLAY 0.872340 (-5525 2350);
DISPLAY INVISIBLE (-5525 2350);
FORCEPROP 1 LAST PATH I45
J 0
(-5852 2475);
DISPLAY 0.872340 (-5852 2475);
PAINT GREEN (-5852 2475);
DISPLAY INVISIBLE (-5852 2475);
FORCEADD TAP..1
(-5850 2575);
FORCEPROP 3 LASTPIN (-5900 2575) SIG_NAME M_J_CPU1_SB_DQ<9>
J 0
(-5890 2585);
DISPLAY 0.659574 (-5890 2585);
PAINT MONO (-5890 2585);
DISPLAY INVISIBLE (-5890 2585);
FORCEPROP 1 LASTPIN (-5900 2575) BN 9
J 0
(-5912 2583);
DISPLAY 0.489362 (-5912 2583);
PAINT GREEN (-5912 2583);
FORCEPROP 2 LAST CDS_LIB mstr_standard
J 0
(-5850 2575);
DISPLAY 0.723404 (-5850 2575);
PAINT MONO (-5850 2575);
DISPLAY INVISIBLE (-5850 2575);
FORCEPROP 1 LAST BODY_TYPE PLUMBING
J 0
(-5850 2625);
DISPLAY 0.872340 (-5850 2625);
PAINT GREEN (-5850 2625);
DISPLAY INVISIBLE (-5850 2625);
FORCEPROP 1 LAST HDL_TAP TRUE
J 0
(-5525 2450);
DISPLAY 0.872340 (-5525 2450);
DISPLAY INVISIBLE (-5525 2450);
FORCEPROP 1 LAST PATH I46
J 0
(-5852 2575);
DISPLAY 0.872340 (-5852 2575);
PAINT GREEN (-5852 2575);
DISPLAY INVISIBLE (-5852 2575);
FORCEADD TAP..1
(-5850 2675);
FORCEPROP 3 LASTPIN (-5900 2675) SIG_NAME M_J_CPU1_SB_DQ<11>
J 0
(-5890 2685);
DISPLAY 0.659574 (-5890 2685);
PAINT MONO (-5890 2685);
DISPLAY INVISIBLE (-5890 2685);
FORCEPROP 1 LASTPIN (-5900 2675) BN 11
J 0
(-5912 2683);
DISPLAY 0.489362 (-5912 2683);
PAINT GREEN (-5912 2683);
FORCEPROP 2 LAST CDS_LIB mstr_standard
J 0
(-5850 2675);
DISPLAY 0.723404 (-5850 2675);
PAINT MONO (-5850 2675);
DISPLAY INVISIBLE (-5850 2675);
FORCEPROP 1 LAST BODY_TYPE PLUMBING
J 0
(-5850 2725);
DISPLAY 0.872340 (-5850 2725);
PAINT GREEN (-5850 2725);
DISPLAY INVISIBLE (-5850 2725);
FORCEPROP 1 LAST HDL_TAP TRUE
J 0
(-5525 2550);
DISPLAY 0.872340 (-5525 2550);
DISPLAY INVISIBLE (-5525 2550);
FORCEPROP 1 LAST PATH I47
J 0
(-5852 2675);
DISPLAY 0.872340 (-5852 2675);
PAINT GREEN (-5852 2675);
DISPLAY INVISIBLE (-5852 2675);
FORCEADD TAP..1
(-5850 2625);
FORCEPROP 3 LASTPIN (-5900 2625) SIG_NAME M_J_CPU1_SB_DQ<10>
J 0
(-5890 2635);
DISPLAY 0.659574 (-5890 2635);
PAINT MONO (-5890 2635);
DISPLAY INVISIBLE (-5890 2635);
FORCEPROP 1 LASTPIN (-5900 2625) BN 10
J 0
(-5912 2633);
DISPLAY 0.489362 (-5912 2633);
PAINT GREEN (-5912 2633);
FORCEPROP 2 LAST CDS_LIB mstr_standard
J 0
(-5850 2625);
DISPLAY 0.723404 (-5850 2625);
PAINT MONO (-5850 2625);
DISPLAY INVISIBLE (-5850 2625);
FORCEPROP 1 LAST BODY_TYPE PLUMBING
J 0
(-5850 2675);
DISPLAY 0.872340 (-5850 2675);
PAINT GREEN (-5850 2675);
DISPLAY INVISIBLE (-5850 2675);
FORCEPROP 1 LAST HDL_TAP TRUE
J 0
(-5525 2500);
DISPLAY 0.872340 (-5525 2500);
DISPLAY INVISIBLE (-5525 2500);
FORCEPROP 1 LAST PATH I48
J 0
(-5852 2625);
DISPLAY 0.872340 (-5852 2625);
PAINT GREEN (-5852 2625);
DISPLAY INVISIBLE (-5852 2625);
FORCEADD TAP..1
(-5850 2725);
FORCEPROP 3 LASTPIN (-5900 2725) SIG_NAME M_J_CPU1_SB_DQ<12>
J 0
(-5890 2735);
DISPLAY 0.659574 (-5890 2735);
PAINT MONO (-5890 2735);
DISPLAY INVISIBLE (-5890 2735);
FORCEPROP 1 LASTPIN (-5900 2725) BN 12
J 0
(-5912 2733);
DISPLAY 0.489362 (-5912 2733);
PAINT GREEN (-5912 2733);
FORCEPROP 2 LAST CDS_LIB mstr_standard
J 0
(-5850 2725);
DISPLAY 0.723404 (-5850 2725);
PAINT MONO (-5850 2725);
DISPLAY INVISIBLE (-5850 2725);
FORCEPROP 1 LAST BODY_TYPE PLUMBING
J 0
(-5850 2775);
DISPLAY 0.872340 (-5850 2775);
PAINT GREEN (-5850 2775);
DISPLAY INVISIBLE (-5850 2775);
FORCEPROP 1 LAST HDL_TAP TRUE
J 0
(-5525 2600);
DISPLAY 0.872340 (-5525 2600);
DISPLAY INVISIBLE (-5525 2600);
FORCEPROP 1 LAST PATH I49
J 0
(-5852 2725);
DISPLAY 0.872340 (-5852 2725);
PAINT GREEN (-5852 2725);
DISPLAY INVISIBLE (-5852 2725);
FORCEADD OFFPAGE..5
(-8150 1925);
FORCEPROP 2 LAST $XR0 46 
J 0
(-8374 1925);
DISPLAY 0.638298 (-8374 1925);
PAINT MONO (-8374 1925);
FORCEPROP 2 LAST PATH I5
J 0
(-8350 1975);
DISPLAY 1.021277 (-8350 1975);
DISPLAY INVISIBLE (-8350 1975);
FORCEPROP 1 LAST COMMENT_BODY TRUE
J 0
(-8050 1850);
DISPLAY 0.872340 (-8050 1850);
PAINT GREEN (-8050 1850);
DISPLAY INVISIBLE (-8050 1850);
FORCEPROP 1 LAST OFFPAGE TRUE
J 0
(-7825 1800);
DISPLAY 0.872340 (-7825 1800);
PAINT GREEN (-7825 1800);
DISPLAY INVISIBLE (-7825 1800);
FORCEPROP 2 LAST CDS_LIB mstr_standard
J 0
(-8150 1925);
DISPLAY 0.808511 (-8150 1925);
DISPLAY INVISIBLE (-8150 1925);
FORCEADD TAP..1
(-5850 2775);
FORCEPROP 3 LASTPIN (-5900 2775) SIG_NAME M_J_CPU1_SB_DQ<13>
J 0
(-5890 2785);
DISPLAY 0.659574 (-5890 2785);
PAINT MONO (-5890 2785);
DISPLAY INVISIBLE (-5890 2785);
FORCEPROP 1 LASTPIN (-5900 2775) BN 13
J 0
(-5912 2783);
DISPLAY 0.489362 (-5912 2783);
PAINT GREEN (-5912 2783);
FORCEPROP 2 LAST CDS_LIB mstr_standard
J 0
(-5850 2775);
DISPLAY 0.723404 (-5850 2775);
PAINT MONO (-5850 2775);
DISPLAY INVISIBLE (-5850 2775);
FORCEPROP 1 LAST BODY_TYPE PLUMBING
J 0
(-5850 2825);
DISPLAY 0.872340 (-5850 2825);
PAINT GREEN (-5850 2825);
DISPLAY INVISIBLE (-5850 2825);
FORCEPROP 1 LAST HDL_TAP TRUE
J 0
(-5525 2650);
DISPLAY 0.872340 (-5525 2650);
DISPLAY INVISIBLE (-5525 2650);
FORCEPROP 1 LAST PATH I50
J 0
(-5852 2775);
DISPLAY 0.872340 (-5852 2775);
PAINT GREEN (-5852 2775);
DISPLAY INVISIBLE (-5852 2775);
FORCEADD TAP..1
(-5850 2825);
FORCEPROP 3 LASTPIN (-5900 2825) SIG_NAME M_J_CPU1_SB_DQ<14>
J 0
(-5890 2835);
DISPLAY 0.659574 (-5890 2835);
PAINT MONO (-5890 2835);
DISPLAY INVISIBLE (-5890 2835);
FORCEPROP 1 LASTPIN (-5900 2825) BN 14
J 0
(-5912 2833);
DISPLAY 0.489362 (-5912 2833);
PAINT GREEN (-5912 2833);
FORCEPROP 2 LAST CDS_LIB mstr_standard
J 0
(-5850 2825);
DISPLAY 0.723404 (-5850 2825);
PAINT MONO (-5850 2825);
DISPLAY INVISIBLE (-5850 2825);
FORCEPROP 1 LAST BODY_TYPE PLUMBING
J 0
(-5850 2875);
DISPLAY 0.872340 (-5850 2875);
PAINT GREEN (-5850 2875);
DISPLAY INVISIBLE (-5850 2875);
FORCEPROP 1 LAST HDL_TAP TRUE
J 0
(-5525 2700);
DISPLAY 0.872340 (-5525 2700);
DISPLAY INVISIBLE (-5525 2700);
FORCEPROP 1 LAST PATH I51
J 0
(-5852 2825);
DISPLAY 0.872340 (-5852 2825);
PAINT GREEN (-5852 2825);
DISPLAY INVISIBLE (-5852 2825);
FORCEADD TAP..1
(-5850 2925);
FORCEPROP 3 LASTPIN (-5900 2925) SIG_NAME M_J_CPU1_SB_DQ<16>
J 0
(-5890 2935);
DISPLAY 0.659574 (-5890 2935);
PAINT MONO (-5890 2935);
DISPLAY INVISIBLE (-5890 2935);
FORCEPROP 1 LASTPIN (-5900 2925) BN 16
J 0
(-5912 2933);
DISPLAY 0.489362 (-5912 2933);
PAINT GREEN (-5912 2933);
FORCEPROP 2 LAST CDS_LIB mstr_standard
J 0
(-5850 2925);
DISPLAY 0.723404 (-5850 2925);
PAINT MONO (-5850 2925);
DISPLAY INVISIBLE (-5850 2925);
FORCEPROP 1 LAST BODY_TYPE PLUMBING
J 0
(-5850 2975);
DISPLAY 0.872340 (-5850 2975);
PAINT GREEN (-5850 2975);
DISPLAY INVISIBLE (-5850 2975);
FORCEPROP 1 LAST HDL_TAP TRUE
J 0
(-5525 2800);
DISPLAY 0.872340 (-5525 2800);
DISPLAY INVISIBLE (-5525 2800);
FORCEPROP 1 LAST PATH I52
J 0
(-5852 2925);
DISPLAY 0.872340 (-5852 2925);
PAINT GREEN (-5852 2925);
DISPLAY INVISIBLE (-5852 2925);
FORCEADD TAP..1
(-5850 2875);
FORCEPROP 3 LASTPIN (-5900 2875) SIG_NAME M_J_CPU1_SB_DQ<15>
J 0
(-5890 2885);
DISPLAY 0.659574 (-5890 2885);
PAINT MONO (-5890 2885);
DISPLAY INVISIBLE (-5890 2885);
FORCEPROP 1 LASTPIN (-5900 2875) BN 15
J 0
(-5912 2883);
DISPLAY 0.489362 (-5912 2883);
PAINT GREEN (-5912 2883);
FORCEPROP 2 LAST CDS_LIB mstr_standard
J 0
(-5850 2875);
DISPLAY 0.723404 (-5850 2875);
PAINT MONO (-5850 2875);
DISPLAY INVISIBLE (-5850 2875);
FORCEPROP 1 LAST BODY_TYPE PLUMBING
J 0
(-5850 2925);
DISPLAY 0.872340 (-5850 2925);
PAINT GREEN (-5850 2925);
DISPLAY INVISIBLE (-5850 2925);
FORCEPROP 1 LAST HDL_TAP TRUE
J 0
(-5525 2750);
DISPLAY 0.872340 (-5525 2750);
DISPLAY INVISIBLE (-5525 2750);
FORCEPROP 1 LAST PATH I53
J 0
(-5852 2875);
DISPLAY 0.872340 (-5852 2875);
PAINT GREEN (-5852 2875);
DISPLAY INVISIBLE (-5852 2875);
FORCEADD TAP..1
(-5850 2975);
FORCEPROP 3 LASTPIN (-5900 2975) SIG_NAME M_J_CPU1_SB_DQ<17>
J 0
(-5890 2985);
DISPLAY 0.659574 (-5890 2985);
PAINT MONO (-5890 2985);
DISPLAY INVISIBLE (-5890 2985);
FORCEPROP 1 LASTPIN (-5900 2975) BN 17
J 0
(-5912 2983);
DISPLAY 0.489362 (-5912 2983);
PAINT GREEN (-5912 2983);
FORCEPROP 2 LAST CDS_LIB mstr_standard
J 0
(-5850 2975);
DISPLAY 0.723404 (-5850 2975);
PAINT MONO (-5850 2975);
DISPLAY INVISIBLE (-5850 2975);
FORCEPROP 1 LAST BODY_TYPE PLUMBING
J 0
(-5850 3025);
DISPLAY 0.872340 (-5850 3025);
PAINT GREEN (-5850 3025);
DISPLAY INVISIBLE (-5850 3025);
FORCEPROP 1 LAST HDL_TAP TRUE
J 0
(-5525 2850);
DISPLAY 0.872340 (-5525 2850);
DISPLAY INVISIBLE (-5525 2850);
FORCEPROP 1 LAST PATH I54
J 0
(-5852 2975);
DISPLAY 0.872340 (-5852 2975);
PAINT GREEN (-5852 2975);
DISPLAY INVISIBLE (-5852 2975);
FORCEADD TAP..1
(-5850 3025);
FORCEPROP 3 LASTPIN (-5900 3025) SIG_NAME M_J_CPU1_SB_DQ<18>
J 0
(-5890 3035);
DISPLAY 0.659574 (-5890 3035);
PAINT MONO (-5890 3035);
DISPLAY INVISIBLE (-5890 3035);
FORCEPROP 1 LASTPIN (-5900 3025) BN 18
J 0
(-5912 3033);
DISPLAY 0.489362 (-5912 3033);
PAINT GREEN (-5912 3033);
FORCEPROP 2 LAST CDS_LIB mstr_standard
J 0
(-5850 3025);
DISPLAY 0.723404 (-5850 3025);
PAINT MONO (-5850 3025);
DISPLAY INVISIBLE (-5850 3025);
FORCEPROP 1 LAST BODY_TYPE PLUMBING
J 0
(-5850 3075);
DISPLAY 0.872340 (-5850 3075);
PAINT GREEN (-5850 3075);
DISPLAY INVISIBLE (-5850 3075);
FORCEPROP 1 LAST HDL_TAP TRUE
J 0
(-5525 2900);
DISPLAY 0.872340 (-5525 2900);
DISPLAY INVISIBLE (-5525 2900);
FORCEPROP 1 LAST PATH I55
J 0
(-5852 3025);
DISPLAY 0.872340 (-5852 3025);
PAINT GREEN (-5852 3025);
DISPLAY INVISIBLE (-5852 3025);
FORCEADD TAP..1
(-5850 3075);
FORCEPROP 3 LASTPIN (-5900 3075) SIG_NAME M_J_CPU1_SB_DQ<19>
J 0
(-5890 3085);
DISPLAY 0.659574 (-5890 3085);
PAINT MONO (-5890 3085);
DISPLAY INVISIBLE (-5890 3085);
FORCEPROP 1 LASTPIN (-5900 3075) BN 19
J 0
(-5912 3083);
DISPLAY 0.489362 (-5912 3083);
PAINT GREEN (-5912 3083);
FORCEPROP 2 LAST CDS_LIB mstr_standard
J 0
(-5850 3075);
DISPLAY 0.723404 (-5850 3075);
PAINT MONO (-5850 3075);
DISPLAY INVISIBLE (-5850 3075);
FORCEPROP 1 LAST BODY_TYPE PLUMBING
J 0
(-5850 3125);
DISPLAY 0.872340 (-5850 3125);
PAINT GREEN (-5850 3125);
DISPLAY INVISIBLE (-5850 3125);
FORCEPROP 1 LAST HDL_TAP TRUE
J 0
(-5525 2950);
DISPLAY 0.872340 (-5525 2950);
DISPLAY INVISIBLE (-5525 2950);
FORCEPROP 1 LAST PATH I56
J 0
(-5852 3075);
DISPLAY 0.872340 (-5852 3075);
PAINT GREEN (-5852 3075);
DISPLAY INVISIBLE (-5852 3075);
FORCEADD TAP..1
(-5850 3125);
FORCEPROP 3 LASTPIN (-5900 3125) SIG_NAME M_J_CPU1_SB_DQ<20>
J 0
(-5890 3135);
DISPLAY 0.659574 (-5890 3135);
PAINT MONO (-5890 3135);
DISPLAY INVISIBLE (-5890 3135);
FORCEPROP 1 LASTPIN (-5900 3125) BN 20
J 0
(-5912 3133);
DISPLAY 0.489362 (-5912 3133);
PAINT GREEN (-5912 3133);
FORCEPROP 2 LAST CDS_LIB mstr_standard
J 0
(-5850 3125);
DISPLAY 0.723404 (-5850 3125);
PAINT MONO (-5850 3125);
DISPLAY INVISIBLE (-5850 3125);
FORCEPROP 1 LAST BODY_TYPE PLUMBING
J 0
(-5850 3175);
DISPLAY 0.872340 (-5850 3175);
PAINT GREEN (-5850 3175);
DISPLAY INVISIBLE (-5850 3175);
FORCEPROP 1 LAST HDL_TAP TRUE
J 0
(-5525 3000);
DISPLAY 0.872340 (-5525 3000);
DISPLAY INVISIBLE (-5525 3000);
FORCEPROP 1 LAST PATH I57
J 0
(-5852 3125);
DISPLAY 0.872340 (-5852 3125);
PAINT GREEN (-5852 3125);
DISPLAY INVISIBLE (-5852 3125);
FORCEADD TAP..1
(-5850 3175);
FORCEPROP 3 LASTPIN (-5900 3175) SIG_NAME M_J_CPU1_SB_DQ<21>
J 0
(-5890 3185);
DISPLAY 0.659574 (-5890 3185);
PAINT MONO (-5890 3185);
DISPLAY INVISIBLE (-5890 3185);
FORCEPROP 1 LASTPIN (-5900 3175) BN 21
J 0
(-5912 3183);
DISPLAY 0.489362 (-5912 3183);
PAINT GREEN (-5912 3183);
FORCEPROP 2 LAST CDS_LIB mstr_standard
J 0
(-5850 3175);
DISPLAY 0.723404 (-5850 3175);
PAINT MONO (-5850 3175);
DISPLAY INVISIBLE (-5850 3175);
FORCEPROP 1 LAST BODY_TYPE PLUMBING
J 0
(-5850 3225);
DISPLAY 0.872340 (-5850 3225);
PAINT GREEN (-5850 3225);
DISPLAY INVISIBLE (-5850 3225);
FORCEPROP 1 LAST HDL_TAP TRUE
J 0
(-5525 3050);
DISPLAY 0.872340 (-5525 3050);
DISPLAY INVISIBLE (-5525 3050);
FORCEPROP 1 LAST PATH I58
J 0
(-5852 3175);
DISPLAY 0.872340 (-5852 3175);
PAINT GREEN (-5852 3175);
DISPLAY INVISIBLE (-5852 3175);
FORCEADD TAP..1
(-5850 3225);
FORCEPROP 3 LASTPIN (-5900 3225) SIG_NAME M_J_CPU1_SB_DQ<22>
J 0
(-5890 3235);
DISPLAY 0.659574 (-5890 3235);
PAINT MONO (-5890 3235);
DISPLAY INVISIBLE (-5890 3235);
FORCEPROP 1 LASTPIN (-5900 3225) BN 22
J 0
(-5912 3233);
DISPLAY 0.489362 (-5912 3233);
PAINT GREEN (-5912 3233);
FORCEPROP 2 LAST CDS_LIB mstr_standard
J 0
(-5850 3225);
DISPLAY 0.723404 (-5850 3225);
PAINT MONO (-5850 3225);
DISPLAY INVISIBLE (-5850 3225);
FORCEPROP 1 LAST BODY_TYPE PLUMBING
J 0
(-5850 3275);
DISPLAY 0.872340 (-5850 3275);
PAINT GREEN (-5850 3275);
DISPLAY INVISIBLE (-5850 3275);
FORCEPROP 1 LAST HDL_TAP TRUE
J 0
(-5525 3100);
DISPLAY 0.872340 (-5525 3100);
DISPLAY INVISIBLE (-5525 3100);
FORCEPROP 1 LAST PATH I59
J 0
(-5852 3225);
DISPLAY 0.872340 (-5852 3225);
PAINT GREEN (-5852 3225);
DISPLAY INVISIBLE (-5852 3225);
FORCEADD OFFPAGE..5
(-8150 1875);
FORCEPROP 2 LAST $XR0 46 
J 0
(-8374 1875);
DISPLAY 0.638298 (-8374 1875);
PAINT MONO (-8374 1875);
FORCEPROP 2 LAST PATH I6
J 0
(-8350 1925);
DISPLAY 1.021277 (-8350 1925);
DISPLAY INVISIBLE (-8350 1925);
FORCEPROP 1 LAST COMMENT_BODY TRUE
J 0
(-8050 1800);
DISPLAY 0.872340 (-8050 1800);
PAINT GREEN (-8050 1800);
DISPLAY INVISIBLE (-8050 1800);
FORCEPROP 1 LAST OFFPAGE TRUE
J 0
(-7825 1750);
DISPLAY 0.872340 (-7825 1750);
PAINT GREEN (-7825 1750);
DISPLAY INVISIBLE (-7825 1750);
FORCEPROP 2 LAST CDS_LIB mstr_standard
J 0
(-8150 1875);
DISPLAY 0.808511 (-8150 1875);
DISPLAY INVISIBLE (-8150 1875);
FORCEADD TAP..1
(-5850 3325);
FORCEPROP 3 LASTPIN (-5900 3325) SIG_NAME M_J_CPU1_SB_DQ<24>
J 0
(-5890 3335);
DISPLAY 0.659574 (-5890 3335);
PAINT MONO (-5890 3335);
DISPLAY INVISIBLE (-5890 3335);
FORCEPROP 1 LASTPIN (-5900 3325) BN 24
J 0
(-5912 3333);
DISPLAY 0.489362 (-5912 3333);
PAINT GREEN (-5912 3333);
FORCEPROP 2 LAST CDS_LIB mstr_standard
J 0
(-5850 3325);
DISPLAY 0.723404 (-5850 3325);
PAINT MONO (-5850 3325);
DISPLAY INVISIBLE (-5850 3325);
FORCEPROP 1 LAST BODY_TYPE PLUMBING
J 0
(-5850 3375);
DISPLAY 0.872340 (-5850 3375);
PAINT GREEN (-5850 3375);
DISPLAY INVISIBLE (-5850 3375);
FORCEPROP 1 LAST HDL_TAP TRUE
J 0
(-5525 3200);
DISPLAY 0.872340 (-5525 3200);
DISPLAY INVISIBLE (-5525 3200);
FORCEPROP 1 LAST PATH I60
J 0
(-5852 3325);
DISPLAY 0.872340 (-5852 3325);
PAINT GREEN (-5852 3325);
DISPLAY INVISIBLE (-5852 3325);
FORCEADD TAP..1
(-5850 3275);
FORCEPROP 3 LASTPIN (-5900 3275) SIG_NAME M_J_CPU1_SB_DQ<23>
J 0
(-5890 3285);
DISPLAY 0.659574 (-5890 3285);
PAINT MONO (-5890 3285);
DISPLAY INVISIBLE (-5890 3285);
FORCEPROP 1 LASTPIN (-5900 3275) BN 23
J 0
(-5912 3283);
DISPLAY 0.489362 (-5912 3283);
PAINT GREEN (-5912 3283);
FORCEPROP 2 LAST CDS_LIB mstr_standard
J 0
(-5850 3275);
DISPLAY 0.723404 (-5850 3275);
PAINT MONO (-5850 3275);
DISPLAY INVISIBLE (-5850 3275);
FORCEPROP 1 LAST BODY_TYPE PLUMBING
J 0
(-5850 3325);
DISPLAY 0.872340 (-5850 3325);
PAINT GREEN (-5850 3325);
DISPLAY INVISIBLE (-5850 3325);
FORCEPROP 1 LAST HDL_TAP TRUE
J 0
(-5525 3150);
DISPLAY 0.872340 (-5525 3150);
DISPLAY INVISIBLE (-5525 3150);
FORCEPROP 1 LAST PATH I61
J 0
(-5852 3275);
DISPLAY 0.872340 (-5852 3275);
PAINT GREEN (-5852 3275);
DISPLAY INVISIBLE (-5852 3275);
FORCEADD TAP..1
(-5850 3375);
FORCEPROP 3 LASTPIN (-5900 3375) SIG_NAME M_J_CPU1_SB_DQ<25>
J 0
(-5890 3385);
DISPLAY 0.659574 (-5890 3385);
PAINT MONO (-5890 3385);
DISPLAY INVISIBLE (-5890 3385);
FORCEPROP 1 LASTPIN (-5900 3375) BN 25
J 0
(-5912 3383);
DISPLAY 0.489362 (-5912 3383);
PAINT GREEN (-5912 3383);
FORCEPROP 2 LAST CDS_LIB mstr_standard
J 0
(-5850 3375);
DISPLAY 0.723404 (-5850 3375);
PAINT MONO (-5850 3375);
DISPLAY INVISIBLE (-5850 3375);
FORCEPROP 1 LAST BODY_TYPE PLUMBING
J 0
(-5850 3425);
DISPLAY 0.872340 (-5850 3425);
PAINT GREEN (-5850 3425);
DISPLAY INVISIBLE (-5850 3425);
FORCEPROP 1 LAST HDL_TAP TRUE
J 0
(-5525 3250);
DISPLAY 0.872340 (-5525 3250);
DISPLAY INVISIBLE (-5525 3250);
FORCEPROP 1 LAST PATH I62
J 0
(-5852 3375);
DISPLAY 0.872340 (-5852 3375);
PAINT GREEN (-5852 3375);
DISPLAY INVISIBLE (-5852 3375);
FORCEADD TAP..1
(-5850 3425);
FORCEPROP 3 LASTPIN (-5900 3425) SIG_NAME M_J_CPU1_SB_DQ<26>
J 0
(-5890 3435);
DISPLAY 0.659574 (-5890 3435);
PAINT MONO (-5890 3435);
DISPLAY INVISIBLE (-5890 3435);
FORCEPROP 1 LASTPIN (-5900 3425) BN 26
J 0
(-5912 3433);
DISPLAY 0.489362 (-5912 3433);
PAINT GREEN (-5912 3433);
FORCEPROP 2 LAST CDS_LIB mstr_standard
J 0
(-5850 3425);
DISPLAY 0.723404 (-5850 3425);
PAINT MONO (-5850 3425);
DISPLAY INVISIBLE (-5850 3425);
FORCEPROP 1 LAST BODY_TYPE PLUMBING
J 0
(-5850 3475);
DISPLAY 0.872340 (-5850 3475);
PAINT GREEN (-5850 3475);
DISPLAY INVISIBLE (-5850 3475);
FORCEPROP 1 LAST HDL_TAP TRUE
J 0
(-5525 3300);
DISPLAY 0.872340 (-5525 3300);
DISPLAY INVISIBLE (-5525 3300);
FORCEPROP 1 LAST PATH I63
J 0
(-5852 3425);
DISPLAY 0.872340 (-5852 3425);
PAINT GREEN (-5852 3425);
DISPLAY INVISIBLE (-5852 3425);
FORCEADD TAP..1
(-5850 3475);
FORCEPROP 3 LASTPIN (-5900 3475) SIG_NAME M_J_CPU1_SB_DQ<27>
J 0
(-5890 3485);
DISPLAY 0.659574 (-5890 3485);
PAINT MONO (-5890 3485);
DISPLAY INVISIBLE (-5890 3485);
FORCEPROP 1 LASTPIN (-5900 3475) BN 27
J 0
(-5912 3483);
DISPLAY 0.489362 (-5912 3483);
PAINT GREEN (-5912 3483);
FORCEPROP 2 LAST CDS_LIB mstr_standard
J 0
(-5850 3475);
DISPLAY 0.723404 (-5850 3475);
PAINT MONO (-5850 3475);
DISPLAY INVISIBLE (-5850 3475);
FORCEPROP 1 LAST BODY_TYPE PLUMBING
J 0
(-5850 3525);
DISPLAY 0.872340 (-5850 3525);
PAINT GREEN (-5850 3525);
DISPLAY INVISIBLE (-5850 3525);
FORCEPROP 1 LAST HDL_TAP TRUE
J 0
(-5525 3350);
DISPLAY 0.872340 (-5525 3350);
DISPLAY INVISIBLE (-5525 3350);
FORCEPROP 1 LAST PATH I64
J 0
(-5852 3475);
DISPLAY 0.872340 (-5852 3475);
PAINT GREEN (-5852 3475);
DISPLAY INVISIBLE (-5852 3475);
FORCEADD TAP..1
(-5850 3575);
FORCEPROP 3 LASTPIN (-5900 3575) SIG_NAME M_J_CPU1_SB_DQ<29>
J 0
(-5890 3585);
DISPLAY 0.659574 (-5890 3585);
PAINT MONO (-5890 3585);
DISPLAY INVISIBLE (-5890 3585);
FORCEPROP 1 LASTPIN (-5900 3575) BN 29
J 0
(-5912 3583);
DISPLAY 0.489362 (-5912 3583);
PAINT GREEN (-5912 3583);
FORCEPROP 2 LAST CDS_LIB mstr_standard
J 0
(-5850 3575);
DISPLAY 0.723404 (-5850 3575);
PAINT MONO (-5850 3575);
DISPLAY INVISIBLE (-5850 3575);
FORCEPROP 1 LAST BODY_TYPE PLUMBING
J 0
(-5850 3625);
DISPLAY 0.872340 (-5850 3625);
PAINT GREEN (-5850 3625);
DISPLAY INVISIBLE (-5850 3625);
FORCEPROP 1 LAST HDL_TAP TRUE
J 0
(-5525 3450);
DISPLAY 0.872340 (-5525 3450);
DISPLAY INVISIBLE (-5525 3450);
FORCEPROP 1 LAST PATH I65
J 0
(-5852 3575);
DISPLAY 0.872340 (-5852 3575);
PAINT GREEN (-5852 3575);
DISPLAY INVISIBLE (-5852 3575);
FORCEADD TAP..1
(-5850 3525);
FORCEPROP 3 LASTPIN (-5900 3525) SIG_NAME M_J_CPU1_SB_DQ<28>
J 0
(-5890 3535);
DISPLAY 0.659574 (-5890 3535);
PAINT MONO (-5890 3535);
DISPLAY INVISIBLE (-5890 3535);
FORCEPROP 1 LASTPIN (-5900 3525) BN 28
J 0
(-5912 3533);
DISPLAY 0.489362 (-5912 3533);
PAINT GREEN (-5912 3533);
FORCEPROP 2 LAST CDS_LIB mstr_standard
J 0
(-5850 3525);
DISPLAY 0.723404 (-5850 3525);
PAINT MONO (-5850 3525);
DISPLAY INVISIBLE (-5850 3525);
FORCEPROP 1 LAST BODY_TYPE PLUMBING
J 0
(-5850 3575);
DISPLAY 0.872340 (-5850 3575);
PAINT GREEN (-5850 3575);
DISPLAY INVISIBLE (-5850 3575);
FORCEPROP 1 LAST HDL_TAP TRUE
J 0
(-5525 3400);
DISPLAY 0.872340 (-5525 3400);
DISPLAY INVISIBLE (-5525 3400);
FORCEPROP 1 LAST PATH I66
J 0
(-5852 3525);
DISPLAY 0.872340 (-5852 3525);
PAINT GREEN (-5852 3525);
DISPLAY INVISIBLE (-5852 3525);
FORCEADD TAP..1
(-5850 3675);
FORCEPROP 3 LASTPIN (-5900 3675) SIG_NAME M_J_CPU1_SB_DQ<31>
J 0
(-5890 3685);
DISPLAY 0.659574 (-5890 3685);
PAINT MONO (-5890 3685);
DISPLAY INVISIBLE (-5890 3685);
FORCEPROP 1 LASTPIN (-5900 3675) BN 31
J 0
(-5912 3683);
DISPLAY 0.489362 (-5912 3683);
PAINT GREEN (-5912 3683);
FORCEPROP 2 LAST CDS_LIB mstr_standard
J 0
(-5850 3675);
DISPLAY 0.723404 (-5850 3675);
PAINT MONO (-5850 3675);
DISPLAY INVISIBLE (-5850 3675);
FORCEPROP 1 LAST BODY_TYPE PLUMBING
J 0
(-5850 3725);
DISPLAY 0.872340 (-5850 3725);
PAINT GREEN (-5850 3725);
DISPLAY INVISIBLE (-5850 3725);
FORCEPROP 1 LAST HDL_TAP TRUE
J 0
(-5525 3550);
DISPLAY 0.872340 (-5525 3550);
DISPLAY INVISIBLE (-5525 3550);
FORCEPROP 1 LAST PATH I67
J 0
(-5852 3675);
DISPLAY 0.872340 (-5852 3675);
PAINT GREEN (-5852 3675);
DISPLAY INVISIBLE (-5852 3675);
FORCEADD TAP..1
(-5850 3625);
FORCEPROP 3 LASTPIN (-5900 3625) SIG_NAME M_J_CPU1_SB_DQ<30>
J 0
(-5890 3635);
DISPLAY 0.659574 (-5890 3635);
PAINT MONO (-5890 3635);
DISPLAY INVISIBLE (-5890 3635);
FORCEPROP 1 LASTPIN (-5900 3625) BN 30
J 0
(-5912 3633);
DISPLAY 0.489362 (-5912 3633);
PAINT GREEN (-5912 3633);
FORCEPROP 2 LAST CDS_LIB mstr_standard
J 0
(-5850 3625);
DISPLAY 0.723404 (-5850 3625);
PAINT MONO (-5850 3625);
DISPLAY INVISIBLE (-5850 3625);
FORCEPROP 1 LAST BODY_TYPE PLUMBING
J 0
(-5850 3675);
DISPLAY 0.872340 (-5850 3675);
PAINT GREEN (-5850 3675);
DISPLAY INVISIBLE (-5850 3675);
FORCEPROP 1 LAST HDL_TAP TRUE
J 0
(-5525 3500);
DISPLAY 0.872340 (-5525 3500);
DISPLAY INVISIBLE (-5525 3500);
FORCEPROP 1 LAST PATH I68
J 0
(-5852 3625);
DISPLAY 0.872340 (-5852 3625);
PAINT GREEN (-5852 3625);
DISPLAY INVISIBLE (-5852 3625);
FORCEADD TAP..1
(-5850 3775);
FORCEPROP 3 LASTPIN (-5900 3775) SIG_NAME M_J_CPU1_SA_DQ<0>
J 0
(-5890 3785);
DISPLAY 0.659574 (-5890 3785);
PAINT MONO (-5890 3785);
DISPLAY INVISIBLE (-5890 3785);
FORCEPROP 1 LASTPIN (-5900 3775) BN 0
J 0
(-5912 3783);
DISPLAY 0.489362 (-5912 3783);
PAINT GREEN (-5912 3783);
FORCEPROP 2 LAST CDS_LIB mstr_standard
J 0
(-5850 3775);
DISPLAY 0.723404 (-5850 3775);
PAINT MONO (-5850 3775);
DISPLAY INVISIBLE (-5850 3775);
FORCEPROP 1 LAST BODY_TYPE PLUMBING
J 0
(-5850 3825);
DISPLAY 0.872340 (-5850 3825);
PAINT GREEN (-5850 3825);
DISPLAY INVISIBLE (-5850 3825);
FORCEPROP 1 LAST HDL_TAP TRUE
J 0
(-5525 3650);
DISPLAY 0.872340 (-5525 3650);
DISPLAY INVISIBLE (-5525 3650);
FORCEPROP 1 LAST PATH I69
J 0
(-5852 3775);
DISPLAY 0.872340 (-5852 3775);
PAINT GREEN (-5852 3775);
DISPLAY INVISIBLE (-5852 3775);
FORCEADD VCC_CORE..1
(-8425 3350);
FORCEPROP 3 LASTPIN (-8425 3300) SIG_NAME P3V3_STBY\g
J 0
(-8415 3310);
DISPLAY 0.659574 (-8415 3310);
PAINT MONO (-8415 3310);
DISPLAY INVISIBLE (-8415 3310);
FORCEPROP 1 LAST HDL_POWER P3V3_STBY
J 1
(-8425 3400);
DISPLAY 0.489362 (-8425 3400);
PAINT GREEN (-8425 3400);
FORCEPROP 2 LAST CDS_LIB mstr_symbols
J 0
(-8425 3350);
PAINT MONO (-8425 3350);
DISPLAY INVISIBLE (-8425 3350);
FORCEPROP 1 LAST PATH I7
J 0
(-8375 3375);
DISPLAY 0.872340 (-8375 3375);
PAINT AQUA (-8375 3375);
DISPLAY INVISIBLE (-8375 3375);
FORCEPROP 0 LAST VOLTAGE 3.3
J 0
(-8700 3500);
DISPLAY 1.021277 (-8700 3500);
PAINT SKYBLUE (-8700 3500);
DISPLAY INVISIBLE (-8700 3500);
FORCEPROP 2 LAST ROOM PVCCINFAON_CPU1_CTRL
J 0
(-8425 3450);
DISPLAY 0.808511 (-8425 3450);
PAINT RED (-8425 3450);
DISPLAY INVISIBLE (-8425 3450);
FORCEADD TAP..1
(-5850 3825);
FORCEPROP 3 LASTPIN (-5900 3825) SIG_NAME M_J_CPU1_SA_DQ<1>
J 0
(-5890 3835);
DISPLAY 0.659574 (-5890 3835);
PAINT MONO (-5890 3835);
DISPLAY INVISIBLE (-5890 3835);
FORCEPROP 1 LASTPIN (-5900 3825) BN 1
J 0
(-5912 3833);
DISPLAY 0.489362 (-5912 3833);
PAINT GREEN (-5912 3833);
FORCEPROP 2 LAST CDS_LIB mstr_standard
J 0
(-5850 3825);
DISPLAY 0.723404 (-5850 3825);
PAINT MONO (-5850 3825);
DISPLAY INVISIBLE (-5850 3825);
FORCEPROP 1 LAST BODY_TYPE PLUMBING
J 0
(-5850 3875);
DISPLAY 0.872340 (-5850 3875);
PAINT GREEN (-5850 3875);
DISPLAY INVISIBLE (-5850 3875);
FORCEPROP 1 LAST HDL_TAP TRUE
J 0
(-5525 3700);
DISPLAY 0.872340 (-5525 3700);
DISPLAY INVISIBLE (-5525 3700);
FORCEPROP 1 LAST PATH I70
J 0
(-5852 3825);
DISPLAY 0.872340 (-5852 3825);
PAINT GREEN (-5852 3825);
DISPLAY INVISIBLE (-5852 3825);
FORCEADD OFFPAGE..3
(-5200 3725);
FORCEPROP 2 LAST $XR0 46 
J 0
(-4986 3725);
DISPLAY 0.638298 (-4986 3725);
PAINT MONO (-4986 3725);
FORCEPROP 2 LAST PATH I78
J 0
(-4975 3775);
DISPLAY 1.021277 (-4975 3775);
DISPLAY INVISIBLE (-4975 3775);
FORCEPROP 1 LAST COMMENT_BODY TRUE
J 0
(-5250 3625);
DISPLAY 0.872340 (-5250 3625);
PAINT GREEN (-5250 3625);
DISPLAY INVISIBLE (-5250 3625);
FORCEPROP 1 LAST OFFPAGE TRUE
J 0
(-4875 3600);
DISPLAY 0.872340 (-4875 3600);
PAINT GREEN (-4875 3600);
DISPLAY INVISIBLE (-4875 3600);
FORCEPROP 2 LAST CDS_LIB mstr_standard
J 0
(-5200 3725);
DISPLAY 0.723404 (-5200 3725);
PAINT MONO (-5200 3725);
DISPLAY INVISIBLE (-5200 3725);
FORCEADD TAP..1
R 2
(-7550 3875);
FORCEPROP 3 LASTPIN (-7500 3875) SIG_NAME M_J_CPU1_SA_CB<6>
J 0
(-7490 3885);
DISPLAY 0.659574 (-7490 3885);
PAINT MONO (-7490 3885);
DISPLAY INVISIBLE (-7490 3885);
FORCEPROP 1 LASTPIN (-7500 3875) BN 6
J 2
(-7488 3883);
DISPLAY 0.489362 (-7488 3883);
PAINT GREEN (-7488 3883);
FORCEPROP 2 LAST CDS_LIB mstr_standard
J 0
(-7550 3875);
DISPLAY 0.723404 (-7550 3875);
PAINT MONO (-7550 3875);
DISPLAY INVISIBLE (-7550 3875);
FORCEPROP 1 LAST BODY_TYPE PLUMBING
J 2
(-7550 3925);
DISPLAY 0.872340 (-7550 3925);
PAINT GREEN (-7550 3925);
DISPLAY INVISIBLE (-7550 3925);
FORCEPROP 1 LAST HDL_TAP TRUE
J 2
(-7875 3750);
DISPLAY 0.872340 (-7875 3750);
DISPLAY INVISIBLE (-7875 3750);
FORCEPROP 1 LAST PATH I79
J 2
(-7548 3875);
DISPLAY 0.872340 (-7548 3875);
PAINT GREEN (-7548 3875);
DISPLAY INVISIBLE (-7548 3875);
FORCEADD OFFPAGE..1
(-7950 3025);
FORCEPROP 2 LAST $XR0 46 
J 0
(-8171 3025);
DISPLAY 0.638298 (-8171 3025);
PAINT MONO (-8171 3025);
FORCEPROP 2 LAST PATH I8
J 0
(-8150 3075);
DISPLAY 1.021277 (-8150 3075);
DISPLAY INVISIBLE (-8150 3075);
FORCEPROP 1 LAST COMMENT_BODY TRUE
J 0
(-7825 2925);
DISPLAY 0.872340 (-7825 2925);
PAINT GREEN (-7825 2925);
DISPLAY INVISIBLE (-7825 2925);
FORCEPROP 1 LAST OFFPAGE TRUE
J 0
(-7625 2900);
DISPLAY 0.872340 (-7625 2900);
PAINT GREEN (-7625 2900);
DISPLAY INVISIBLE (-7625 2900);
FORCEPROP 2 LAST CDS_LIB mstr_standard
J 0
(-7950 3025);
DISPLAY 0.808511 (-7950 3025);
DISPLAY INVISIBLE (-7950 3025);
FORCEADD TAP..1
R 2
(-7550 3925);
FORCEPROP 3 LASTPIN (-7500 3925) SIG_NAME M_J_CPU1_SA_CB<7>
J 0
(-7490 3935);
DISPLAY 0.659574 (-7490 3935);
PAINT MONO (-7490 3935);
DISPLAY INVISIBLE (-7490 3935);
FORCEPROP 1 LASTPIN (-7500 3925) BN 7
J 2
(-7488 3933);
DISPLAY 0.489362 (-7488 3933);
PAINT GREEN (-7488 3933);
FORCEPROP 2 LAST CDS_LIB mstr_standard
J 0
(-7550 3925);
DISPLAY 0.723404 (-7550 3925);
PAINT MONO (-7550 3925);
DISPLAY INVISIBLE (-7550 3925);
FORCEPROP 1 LAST BODY_TYPE PLUMBING
J 2
(-7550 3975);
DISPLAY 0.872340 (-7550 3975);
PAINT GREEN (-7550 3975);
DISPLAY INVISIBLE (-7550 3975);
FORCEPROP 1 LAST HDL_TAP TRUE
J 2
(-7875 3800);
DISPLAY 0.872340 (-7875 3800);
DISPLAY INVISIBLE (-7875 3800);
FORCEPROP 1 LAST PATH I80
J 2
(-7548 3925);
DISPLAY 0.872340 (-7548 3925);
PAINT GREEN (-7548 3925);
DISPLAY INVISIBLE (-7548 3925);
FORCEADD TAP..1
R 2
(-7550 4625);
FORCEPROP 3 LASTPIN (-7500 4625) SIG_NAME M_J_CPU1_SB_CA<0>
J 0
(-7490 4635);
DISPLAY 0.659574 (-7490 4635);
PAINT MONO (-7490 4635);
DISPLAY INVISIBLE (-7490 4635);
FORCEPROP 1 LASTPIN (-7500 4625) BN 0
J 2
(-7488 4633);
DISPLAY 0.489362 (-7488 4633);
PAINT GREEN (-7488 4633);
FORCEPROP 2 LAST CDS_LIB mstr_standard
J 0
(-7550 4625);
DISPLAY 0.723404 (-7550 4625);
PAINT MONO (-7550 4625);
DISPLAY INVISIBLE (-7550 4625);
FORCEPROP 1 LAST BODY_TYPE PLUMBING
J 2
(-7550 4675);
DISPLAY 0.872340 (-7550 4675);
PAINT GREEN (-7550 4675);
DISPLAY INVISIBLE (-7550 4675);
FORCEPROP 1 LAST HDL_TAP TRUE
J 2
(-7875 4500);
DISPLAY 0.872340 (-7875 4500);
DISPLAY INVISIBLE (-7875 4500);
FORCEPROP 1 LAST PATH I81
J 2
(-7548 4625);
DISPLAY 0.872340 (-7548 4625);
PAINT GREEN (-7548 4625);
DISPLAY INVISIBLE (-7548 4625);
FORCEADD TAP..1
R 2
(-7550 4725);
FORCEPROP 3 LASTPIN (-7500 4725) SIG_NAME M_J_CPU1_SB_CA<2>
J 0
(-7490 4735);
DISPLAY 0.659574 (-7490 4735);
PAINT MONO (-7490 4735);
DISPLAY INVISIBLE (-7490 4735);
FORCEPROP 1 LASTPIN (-7500 4725) BN 2
J 2
(-7488 4733);
DISPLAY 0.489362 (-7488 4733);
PAINT GREEN (-7488 4733);
FORCEPROP 2 LAST CDS_LIB mstr_standard
J 0
(-7550 4725);
DISPLAY 0.723404 (-7550 4725);
PAINT MONO (-7550 4725);
DISPLAY INVISIBLE (-7550 4725);
FORCEPROP 1 LAST BODY_TYPE PLUMBING
J 2
(-7550 4775);
DISPLAY 0.872340 (-7550 4775);
PAINT GREEN (-7550 4775);
DISPLAY INVISIBLE (-7550 4775);
FORCEPROP 1 LAST HDL_TAP TRUE
J 2
(-7875 4600);
DISPLAY 0.872340 (-7875 4600);
DISPLAY INVISIBLE (-7875 4600);
FORCEPROP 1 LAST PATH I82
J 2
(-7548 4725);
DISPLAY 0.872340 (-7548 4725);
PAINT GREEN (-7548 4725);
DISPLAY INVISIBLE (-7548 4725);
FORCEADD TAP..1
R 2
(-7550 4675);
FORCEPROP 3 LASTPIN (-7500 4675) SIG_NAME M_J_CPU1_SB_CA<1>
J 0
(-7490 4685);
DISPLAY 0.659574 (-7490 4685);
PAINT MONO (-7490 4685);
DISPLAY INVISIBLE (-7490 4685);
FORCEPROP 1 LASTPIN (-7500 4675) BN 1
J 2
(-7488 4683);
DISPLAY 0.489362 (-7488 4683);
PAINT GREEN (-7488 4683);
FORCEPROP 2 LAST CDS_LIB mstr_standard
J 0
(-7550 4675);
DISPLAY 0.723404 (-7550 4675);
PAINT MONO (-7550 4675);
DISPLAY INVISIBLE (-7550 4675);
FORCEPROP 1 LAST BODY_TYPE PLUMBING
J 2
(-7550 4725);
DISPLAY 0.872340 (-7550 4725);
PAINT GREEN (-7550 4725);
DISPLAY INVISIBLE (-7550 4725);
FORCEPROP 1 LAST HDL_TAP TRUE
J 2
(-7875 4550);
DISPLAY 0.872340 (-7875 4550);
DISPLAY INVISIBLE (-7875 4550);
FORCEPROP 1 LAST PATH I83
J 2
(-7548 4675);
DISPLAY 0.872340 (-7548 4675);
PAINT GREEN (-7548 4675);
DISPLAY INVISIBLE (-7548 4675);
FORCEADD TAP..1
R 2
(-7550 4825);
FORCEPROP 3 LASTPIN (-7500 4825) SIG_NAME M_J_CPU1_SB_CA<4>
J 0
(-7490 4835);
DISPLAY 0.659574 (-7490 4835);
PAINT MONO (-7490 4835);
DISPLAY INVISIBLE (-7490 4835);
FORCEPROP 1 LASTPIN (-7500 4825) BN 4
J 2
(-7488 4833);
DISPLAY 0.489362 (-7488 4833);
PAINT GREEN (-7488 4833);
FORCEPROP 2 LAST CDS_LIB mstr_standard
J 0
(-7550 4825);
DISPLAY 0.723404 (-7550 4825);
PAINT MONO (-7550 4825);
DISPLAY INVISIBLE (-7550 4825);
FORCEPROP 1 LAST BODY_TYPE PLUMBING
J 2
(-7550 4875);
DISPLAY 0.872340 (-7550 4875);
PAINT GREEN (-7550 4875);
DISPLAY INVISIBLE (-7550 4875);
FORCEPROP 1 LAST HDL_TAP TRUE
J 2
(-7875 4700);
DISPLAY 0.872340 (-7875 4700);
DISPLAY INVISIBLE (-7875 4700);
FORCEPROP 1 LAST PATH I84
J 2
(-7548 4825);
DISPLAY 0.872340 (-7548 4825);
PAINT GREEN (-7548 4825);
DISPLAY INVISIBLE (-7548 4825);
FORCEADD TAP..1
R 2
(-7550 4775);
FORCEPROP 3 LASTPIN (-7500 4775) SIG_NAME M_J_CPU1_SB_CA<3>
J 0
(-7490 4785);
DISPLAY 0.659574 (-7490 4785);
PAINT MONO (-7490 4785);
DISPLAY INVISIBLE (-7490 4785);
FORCEPROP 1 LASTPIN (-7500 4775) BN 3
J 2
(-7488 4783);
DISPLAY 0.489362 (-7488 4783);
PAINT GREEN (-7488 4783);
FORCEPROP 2 LAST CDS_LIB mstr_standard
J 0
(-7550 4775);
DISPLAY 0.723404 (-7550 4775);
PAINT MONO (-7550 4775);
DISPLAY INVISIBLE (-7550 4775);
FORCEPROP 1 LAST BODY_TYPE PLUMBING
J 2
(-7550 4825);
DISPLAY 0.872340 (-7550 4825);
PAINT GREEN (-7550 4825);
DISPLAY INVISIBLE (-7550 4825);
FORCEPROP 1 LAST HDL_TAP TRUE
J 2
(-7875 4650);
DISPLAY 0.872340 (-7875 4650);
DISPLAY INVISIBLE (-7875 4650);
FORCEPROP 1 LAST PATH I85
J 2
(-7548 4775);
DISPLAY 0.872340 (-7548 4775);
PAINT GREEN (-7548 4775);
DISPLAY INVISIBLE (-7548 4775);
FORCEADD TAP..1
R 2
(-7550 4875);
FORCEPROP 3 LASTPIN (-7500 4875) SIG_NAME M_J_CPU1_SB_CA<5>
J 0
(-7490 4885);
DISPLAY 0.659574 (-7490 4885);
PAINT MONO (-7490 4885);
DISPLAY INVISIBLE (-7490 4885);
FORCEPROP 1 LASTPIN (-7500 4875) BN 5
J 2
(-7488 4883);
DISPLAY 0.489362 (-7488 4883);
PAINT GREEN (-7488 4883);
FORCEPROP 2 LAST CDS_LIB mstr_standard
J 0
(-7550 4875);
DISPLAY 0.723404 (-7550 4875);
PAINT MONO (-7550 4875);
DISPLAY INVISIBLE (-7550 4875);
FORCEPROP 1 LAST BODY_TYPE PLUMBING
J 2
(-7550 4925);
DISPLAY 0.872340 (-7550 4925);
PAINT GREEN (-7550 4925);
DISPLAY INVISIBLE (-7550 4925);
FORCEPROP 1 LAST HDL_TAP TRUE
J 2
(-7875 4750);
DISPLAY 0.872340 (-7875 4750);
DISPLAY INVISIBLE (-7875 4750);
FORCEPROP 1 LAST PATH I86
J 2
(-7548 4875);
DISPLAY 0.872340 (-7548 4875);
PAINT GREEN (-7548 4875);
DISPLAY INVISIBLE (-7548 4875);
FORCEADD TAP..1
R 2
(-7550 4925);
FORCEPROP 3 LASTPIN (-7500 4925) SIG_NAME M_J_CPU1_SB_CA<6>
J 0
(-7490 4935);
DISPLAY 0.659574 (-7490 4935);
PAINT MONO (-7490 4935);
DISPLAY INVISIBLE (-7490 4935);
FORCEPROP 1 LASTPIN (-7500 4925) BN 6
J 2
(-7488 4933);
DISPLAY 0.489362 (-7488 4933);
PAINT GREEN (-7488 4933);
FORCEPROP 2 LAST CDS_LIB mstr_standard
J 0
(-7550 4925);
DISPLAY 0.723404 (-7550 4925);
PAINT MONO (-7550 4925);
DISPLAY INVISIBLE (-7550 4925);
FORCEPROP 1 LAST BODY_TYPE PLUMBING
J 2
(-7550 4975);
DISPLAY 0.872340 (-7550 4975);
PAINT GREEN (-7550 4975);
DISPLAY INVISIBLE (-7550 4975);
FORCEPROP 1 LAST HDL_TAP TRUE
J 2
(-7875 4800);
DISPLAY 0.872340 (-7875 4800);
DISPLAY INVISIBLE (-7875 4800);
FORCEPROP 1 LAST PATH I87
J 2
(-7548 4925);
DISPLAY 0.872340 (-7548 4925);
PAINT GREEN (-7548 4925);
DISPLAY INVISIBLE (-7548 4925);
FORCEADD TAP..1
R 2
(-7550 5025);
FORCEPROP 3 LASTPIN (-7500 5025) SIG_NAME M_J_CPU1_SA_CA<0>
J 0
(-7490 5035);
DISPLAY 0.659574 (-7490 5035);
PAINT MONO (-7490 5035);
DISPLAY INVISIBLE (-7490 5035);
FORCEPROP 1 LASTPIN (-7500 5025) BN 0
J 2
(-7488 5033);
DISPLAY 0.489362 (-7488 5033);
PAINT GREEN (-7488 5033);
FORCEPROP 2 LAST CDS_LIB mstr_standard
J 0
(-7550 5025);
DISPLAY 0.723404 (-7550 5025);
PAINT MONO (-7550 5025);
DISPLAY INVISIBLE (-7550 5025);
FORCEPROP 1 LAST BODY_TYPE PLUMBING
J 2
(-7550 5075);
DISPLAY 0.872340 (-7550 5075);
PAINT GREEN (-7550 5075);
DISPLAY INVISIBLE (-7550 5075);
FORCEPROP 1 LAST HDL_TAP TRUE
J 2
(-7875 4900);
DISPLAY 0.872340 (-7875 4900);
DISPLAY INVISIBLE (-7875 4900);
FORCEPROP 1 LAST PATH I88
J 2
(-7548 5025);
DISPLAY 0.872340 (-7548 5025);
PAINT GREEN (-7548 5025);
DISPLAY INVISIBLE (-7548 5025);
FORCEADD TAP..1
R 2
(-7550 5075);
FORCEPROP 3 LASTPIN (-7500 5075) SIG_NAME M_J_CPU1_SA_CA<1>
J 0
(-7490 5085);
DISPLAY 0.659574 (-7490 5085);
PAINT MONO (-7490 5085);
DISPLAY INVISIBLE (-7490 5085);
FORCEPROP 1 LASTPIN (-7500 5075) BN 1
J 2
(-7488 5083);
DISPLAY 0.489362 (-7488 5083);
PAINT GREEN (-7488 5083);
FORCEPROP 2 LAST CDS_LIB mstr_standard
J 0
(-7550 5075);
DISPLAY 0.723404 (-7550 5075);
PAINT MONO (-7550 5075);
DISPLAY INVISIBLE (-7550 5075);
FORCEPROP 1 LAST BODY_TYPE PLUMBING
J 2
(-7550 5125);
DISPLAY 0.872340 (-7550 5125);
PAINT GREEN (-7550 5125);
DISPLAY INVISIBLE (-7550 5125);
FORCEPROP 1 LAST HDL_TAP TRUE
J 2
(-7875 4950);
DISPLAY 0.872340 (-7875 4950);
DISPLAY INVISIBLE (-7875 4950);
FORCEPROP 1 LAST PATH I89
J 2
(-7548 5075);
DISPLAY 0.872340 (-7548 5075);
PAINT GREEN (-7548 5075);
DISPLAY INVISIBLE (-7548 5075);
FORCEADD OFFPAGE..5
(-7950 2975);
FORCEPROP 2 LAST $XR0 46 
J 0
(-8204 2975);
DISPLAY 0.638298 (-8204 2975);
PAINT MONO (-8204 2975);
FORCEPROP 2 LAST PATH I9
J 0
(-8200 3025);
DISPLAY 1.021277 (-8200 3025);
DISPLAY INVISIBLE (-8200 3025);
FORCEPROP 1 LAST COMMENT_BODY TRUE
J 0
(-7850 2900);
DISPLAY 0.872340 (-7850 2900);
PAINT GREEN (-7850 2900);
DISPLAY INVISIBLE (-7850 2900);
FORCEPROP 1 LAST OFFPAGE TRUE
J 0
(-7625 2850);
DISPLAY 0.872340 (-7625 2850);
PAINT GREEN (-7625 2850);
DISPLAY INVISIBLE (-7625 2850);
FORCEPROP 2 LAST CDS_LIB mstr_standard
J 0
(-7950 2975);
DISPLAY INVISIBLE (-7950 2975);
FORCEADD TAP..1
R 2
(-7550 5125);
FORCEPROP 3 LASTPIN (-7500 5125) SIG_NAME M_J_CPU1_SA_CA<2>
J 0
(-7490 5135);
DISPLAY 0.659574 (-7490 5135);
PAINT MONO (-7490 5135);
DISPLAY INVISIBLE (-7490 5135);
FORCEPROP 1 LASTPIN (-7500 5125) BN 2
J 2
(-7488 5133);
DISPLAY 0.489362 (-7488 5133);
PAINT GREEN (-7488 5133);
FORCEPROP 2 LAST CDS_LIB mstr_standard
J 0
(-7550 5125);
DISPLAY 0.723404 (-7550 5125);
PAINT MONO (-7550 5125);
DISPLAY INVISIBLE (-7550 5125);
FORCEPROP 1 LAST BODY_TYPE PLUMBING
J 2
(-7550 5175);
DISPLAY 0.872340 (-7550 5175);
PAINT GREEN (-7550 5175);
DISPLAY INVISIBLE (-7550 5175);
FORCEPROP 1 LAST HDL_TAP TRUE
J 2
(-7875 5000);
DISPLAY 0.872340 (-7875 5000);
DISPLAY INVISIBLE (-7875 5000);
FORCEPROP 1 LAST PATH I90
J 2
(-7548 5125);
DISPLAY 0.872340 (-7548 5125);
PAINT GREEN (-7548 5125);
DISPLAY INVISIBLE (-7548 5125);
FORCEADD TAP..1
R 2
(-7550 5175);
FORCEPROP 3 LASTPIN (-7500 5175) SIG_NAME M_J_CPU1_SA_CA<3>
J 0
(-7490 5185);
DISPLAY 0.659574 (-7490 5185);
PAINT MONO (-7490 5185);
DISPLAY INVISIBLE (-7490 5185);
FORCEPROP 1 LASTPIN (-7500 5175) BN 3
J 2
(-7488 5183);
DISPLAY 0.489362 (-7488 5183);
PAINT GREEN (-7488 5183);
FORCEPROP 2 LAST CDS_LIB mstr_standard
J 0
(-7550 5175);
DISPLAY 0.723404 (-7550 5175);
PAINT MONO (-7550 5175);
DISPLAY INVISIBLE (-7550 5175);
FORCEPROP 1 LAST BODY_TYPE PLUMBING
J 2
(-7550 5225);
DISPLAY 0.872340 (-7550 5225);
PAINT GREEN (-7550 5225);
DISPLAY INVISIBLE (-7550 5225);
FORCEPROP 1 LAST HDL_TAP TRUE
J 2
(-7875 5050);
DISPLAY 0.872340 (-7875 5050);
DISPLAY INVISIBLE (-7875 5050);
FORCEPROP 1 LAST PATH I91
J 2
(-7548 5175);
DISPLAY 0.872340 (-7548 5175);
PAINT GREEN (-7548 5175);
DISPLAY INVISIBLE (-7548 5175);
FORCEADD TAP..1
R 2
(-7550 5225);
FORCEPROP 3 LASTPIN (-7500 5225) SIG_NAME M_J_CPU1_SA_CA<4>
J 0
(-7490 5235);
DISPLAY 0.659574 (-7490 5235);
PAINT MONO (-7490 5235);
DISPLAY INVISIBLE (-7490 5235);
FORCEPROP 1 LASTPIN (-7500 5225) BN 4
J 2
(-7488 5233);
DISPLAY 0.489362 (-7488 5233);
PAINT GREEN (-7488 5233);
FORCEPROP 2 LAST CDS_LIB mstr_standard
J 0
(-7550 5225);
DISPLAY 0.723404 (-7550 5225);
PAINT MONO (-7550 5225);
DISPLAY INVISIBLE (-7550 5225);
FORCEPROP 1 LAST BODY_TYPE PLUMBING
J 2
(-7550 5275);
DISPLAY 0.872340 (-7550 5275);
PAINT GREEN (-7550 5275);
DISPLAY INVISIBLE (-7550 5275);
FORCEPROP 1 LAST HDL_TAP TRUE
J 2
(-7875 5100);
DISPLAY 0.872340 (-7875 5100);
DISPLAY INVISIBLE (-7875 5100);
FORCEPROP 1 LAST PATH I92
J 2
(-7548 5225);
DISPLAY 0.872340 (-7548 5225);
PAINT GREEN (-7548 5225);
DISPLAY INVISIBLE (-7548 5225);
FORCEADD TAP..1
R 2
(-7550 5275);
FORCEPROP 3 LASTPIN (-7500 5275) SIG_NAME M_J_CPU1_SA_CA<5>
J 0
(-7490 5285);
DISPLAY 0.659574 (-7490 5285);
PAINT MONO (-7490 5285);
DISPLAY INVISIBLE (-7490 5285);
FORCEPROP 1 LASTPIN (-7500 5275) BN 5
J 2
(-7488 5283);
DISPLAY 0.489362 (-7488 5283);
PAINT GREEN (-7488 5283);
FORCEPROP 2 LAST CDS_LIB mstr_standard
J 0
(-7550 5275);
DISPLAY 0.723404 (-7550 5275);
PAINT MONO (-7550 5275);
DISPLAY INVISIBLE (-7550 5275);
FORCEPROP 1 LAST BODY_TYPE PLUMBING
J 2
(-7550 5325);
DISPLAY 0.872340 (-7550 5325);
PAINT GREEN (-7550 5325);
DISPLAY INVISIBLE (-7550 5325);
FORCEPROP 1 LAST HDL_TAP TRUE
J 2
(-7875 5150);
DISPLAY 0.872340 (-7875 5150);
DISPLAY INVISIBLE (-7875 5150);
FORCEPROP 1 LAST PATH I93
J 2
(-7548 5275);
DISPLAY 0.872340 (-7548 5275);
PAINT GREEN (-7548 5275);
DISPLAY INVISIBLE (-7548 5275);
FORCEADD TAP..1
R 2
(-7550 5325);
FORCEPROP 3 LASTPIN (-7500 5325) SIG_NAME M_J_CPU1_SA_CA<6>
J 0
(-7490 5335);
DISPLAY 0.659574 (-7490 5335);
PAINT MONO (-7490 5335);
DISPLAY INVISIBLE (-7490 5335);
FORCEPROP 1 LASTPIN (-7500 5325) BN 6
J 2
(-7488 5333);
DISPLAY 0.489362 (-7488 5333);
PAINT GREEN (-7488 5333);
FORCEPROP 2 LAST CDS_LIB mstr_standard
J 0
(-7550 5325);
DISPLAY 0.723404 (-7550 5325);
PAINT MONO (-7550 5325);
DISPLAY INVISIBLE (-7550 5325);
FORCEPROP 1 LAST BODY_TYPE PLUMBING
J 2
(-7550 5375);
DISPLAY 0.872340 (-7550 5375);
PAINT GREEN (-7550 5375);
DISPLAY INVISIBLE (-7550 5375);
FORCEPROP 1 LAST HDL_TAP TRUE
J 2
(-7875 5200);
DISPLAY 0.872340 (-7875 5200);
DISPLAY INVISIBLE (-7875 5200);
FORCEPROP 1 LAST PATH I94
J 2
(-7548 5325);
DISPLAY 0.872340 (-7548 5325);
PAINT GREEN (-7548 5325);
DISPLAY INVISIBLE (-7548 5325);
FORCEADD TAP..1
(-5850 3875);
FORCEPROP 3 LASTPIN (-5900 3875) SIG_NAME M_J_CPU1_SA_DQ<2>
J 0
(-5890 3885);
DISPLAY 0.659574 (-5890 3885);
PAINT MONO (-5890 3885);
DISPLAY INVISIBLE (-5890 3885);
FORCEPROP 1 LASTPIN (-5900 3875) BN 2
J 0
(-5912 3883);
DISPLAY 0.489362 (-5912 3883);
PAINT GREEN (-5912 3883);
FORCEPROP 2 LAST CDS_LIB mstr_standard
J 0
(-5850 3875);
DISPLAY 0.723404 (-5850 3875);
PAINT MONO (-5850 3875);
DISPLAY INVISIBLE (-5850 3875);
FORCEPROP 1 LAST BODY_TYPE PLUMBING
J 0
(-5850 3925);
DISPLAY 0.872340 (-5850 3925);
PAINT GREEN (-5850 3925);
DISPLAY INVISIBLE (-5850 3925);
FORCEPROP 1 LAST HDL_TAP TRUE
J 0
(-5525 3750);
DISPLAY 0.872340 (-5525 3750);
DISPLAY INVISIBLE (-5525 3750);
FORCEPROP 1 LAST PATH I95
J 0
(-5852 3875);
DISPLAY 0.872340 (-5852 3875);
PAINT GREEN (-5852 3875);
DISPLAY INVISIBLE (-5852 3875);
FORCEADD TAP..1
(-5850 3925);
FORCEPROP 3 LASTPIN (-5900 3925) SIG_NAME M_J_CPU1_SA_DQ<3>
J 0
(-5890 3935);
DISPLAY 0.659574 (-5890 3935);
PAINT MONO (-5890 3935);
DISPLAY INVISIBLE (-5890 3935);
FORCEPROP 1 LASTPIN (-5900 3925) BN 3
J 0
(-5912 3933);
DISPLAY 0.489362 (-5912 3933);
PAINT GREEN (-5912 3933);
FORCEPROP 2 LAST CDS_LIB mstr_standard
J 0
(-5850 3925);
DISPLAY 0.723404 (-5850 3925);
PAINT MONO (-5850 3925);
DISPLAY INVISIBLE (-5850 3925);
FORCEPROP 1 LAST BODY_TYPE PLUMBING
J 0
(-5850 3975);
DISPLAY 0.872340 (-5850 3975);
PAINT GREEN (-5850 3975);
DISPLAY INVISIBLE (-5850 3975);
FORCEPROP 1 LAST HDL_TAP TRUE
J 0
(-5525 3800);
DISPLAY 0.872340 (-5525 3800);
DISPLAY INVISIBLE (-5525 3800);
FORCEPROP 1 LAST PATH I96
J 0
(-5852 3925);
DISPLAY 0.872340 (-5852 3925);
PAINT GREEN (-5852 3925);
DISPLAY INVISIBLE (-5852 3925);
FORCEADD TAP..1
(-5850 3975);
FORCEPROP 3 LASTPIN (-5900 3975) SIG_NAME M_J_CPU1_SA_DQ<4>
J 0
(-5890 3985);
DISPLAY 0.659574 (-5890 3985);
PAINT MONO (-5890 3985);
DISPLAY INVISIBLE (-5890 3985);
FORCEPROP 1 LASTPIN (-5900 3975) BN 4
J 0
(-5912 3983);
DISPLAY 0.489362 (-5912 3983);
PAINT GREEN (-5912 3983);
FORCEPROP 2 LAST CDS_LIB mstr_standard
J 0
(-5850 3975);
DISPLAY 0.723404 (-5850 3975);
PAINT MONO (-5850 3975);
DISPLAY INVISIBLE (-5850 3975);
FORCEPROP 1 LAST BODY_TYPE PLUMBING
J 0
(-5850 4025);
DISPLAY 0.872340 (-5850 4025);
PAINT GREEN (-5850 4025);
DISPLAY INVISIBLE (-5850 4025);
FORCEPROP 1 LAST HDL_TAP TRUE
J 0
(-5525 3850);
DISPLAY 0.872340 (-5525 3850);
DISPLAY INVISIBLE (-5525 3850);
FORCEPROP 1 LAST PATH I97
J 0
(-5852 3975);
DISPLAY 0.872340 (-5852 3975);
PAINT GREEN (-5852 3975);
DISPLAY INVISIBLE (-5852 3975);
FORCEADD TAP..1
(-5850 4025);
FORCEPROP 3 LASTPIN (-5900 4025) SIG_NAME M_J_CPU1_SA_DQ<5>
J 0
(-5890 4035);
DISPLAY 0.659574 (-5890 4035);
PAINT MONO (-5890 4035);
DISPLAY INVISIBLE (-5890 4035);
FORCEPROP 1 LASTPIN (-5900 4025) BN 5
J 0
(-5912 4033);
DISPLAY 0.489362 (-5912 4033);
PAINT GREEN (-5912 4033);
FORCEPROP 2 LAST CDS_LIB mstr_standard
J 0
(-5850 4025);
DISPLAY 0.723404 (-5850 4025);
PAINT MONO (-5850 4025);
DISPLAY INVISIBLE (-5850 4025);
FORCEPROP 1 LAST BODY_TYPE PLUMBING
J 0
(-5850 4075);
DISPLAY 0.872340 (-5850 4075);
PAINT GREEN (-5850 4075);
DISPLAY INVISIBLE (-5850 4075);
FORCEPROP 1 LAST HDL_TAP TRUE
J 0
(-5525 3900);
DISPLAY 0.872340 (-5525 3900);
DISPLAY INVISIBLE (-5525 3900);
FORCEPROP 1 LAST PATH I98
J 0
(-5852 4025);
DISPLAY 0.872340 (-5852 4025);
PAINT GREEN (-5852 4025);
DISPLAY INVISIBLE (-5852 4025);
FORCEADD TAP..1
(-5850 4075);
FORCEPROP 3 LASTPIN (-5900 4075) SIG_NAME M_J_CPU1_SA_DQ<6>
J 0
(-5890 4085);
DISPLAY 0.659574 (-5890 4085);
PAINT MONO (-5890 4085);
DISPLAY INVISIBLE (-5890 4085);
FORCEPROP 1 LASTPIN (-5900 4075) BN 6
J 0
(-5912 4083);
DISPLAY 0.489362 (-5912 4083);
PAINT GREEN (-5912 4083);
FORCEPROP 2 LAST CDS_LIB mstr_standard
J 0
(-5850 4075);
DISPLAY 0.723404 (-5850 4075);
PAINT MONO (-5850 4075);
DISPLAY INVISIBLE (-5850 4075);
FORCEPROP 1 LAST BODY_TYPE PLUMBING
J 0
(-5850 4125);
DISPLAY 0.872340 (-5850 4125);
PAINT GREEN (-5850 4125);
DISPLAY INVISIBLE (-5850 4125);
FORCEPROP 1 LAST HDL_TAP TRUE
J 0
(-5525 3950);
DISPLAY 0.872340 (-5525 3950);
DISPLAY INVISIBLE (-5525 3950);
FORCEPROP 1 LAST PATH I99
J 0
(-5852 4075);
DISPLAY 0.872340 (-5852 4075);
PAINT GREEN (-5852 4075);
DISPLAY INVISIBLE (-5852 4075);
FORCEADD DNS..2
(-8225 2225);
PAINT RED (-8225 2225);
FORCEPROP 2 LAST CDS_LIB mstr_misc
J 0
(-8225 2225);
DISPLAY INVISIBLE (-8225 2225);
FORCEPROP 1 LAST COMMENT_BODY TRUE
R 1
J 0
(-8150 2000);
DISPLAY 0.872340 (-8150 2000);
PAINT PEACH (-8150 2000);
DISPLAY INVISIBLE (-8150 2000);
FORCEADD QUANTA_TITLE_BLOCK_C..1
(0 0);
FORCEPROP 0 LAST CDS_CON_LAST_MODIFIED Fri Mar 11 14:53:08 2022
J 0
(-1885 15);
DISPLAY INVISIBLE (-1885 15);
FORCEPROP 1 LAST CUSTOM_TXT_CDS <CON_LAST_MODIFIED>
J 0
(-1885 15);
DISPLAY 0.978723 (-1885 15);
FORCEPROP 2 LAST CUSTOM_TXT_CDS <XR_PAGE_TITLE>
J 0
(-7890 5250);
DISPLAY 0.638298 (-7890 5250);
PAINT PINK (-7890 5250);
DISPLAY INVISIBLE (-7890 5250);
FORCEPROP 1 LAST CUSTOM_TXT_CDS <NAME_2>
J 0
(-3175 50);
FORCEPROP 1 LAST CUSTOM_TXT_CDS <NAME_1>
J 0
(-3175 175);
FORCEPROP 1 LAST CUSTOM_TXT_CDS <Q_NUMBER>
J 0
(-1403 103);
DISPLAY 1.212766 (-1403 103);
FORCEPROP 1 LAST CUSTOM_TXT_CDS <Q_PROJ>
J 0
(-2382 102);
DISPLAY 1.212766 (-2382 102);
FORCEPROP 1 LAST CUSTOM_TXT_CDS <Q_REV>
J 0
(-184 103);
DISPLAY 1.212766 (-184 103);
FORCEPROP 1 LAST CUSTOM_TXT_CDS <CON_PAGE_NUM> OF <CON_TOTAL_PAGES>
J 0
(-446 18);
DISPLAY 0.978723 (-446 18);
FORCEPROP 1 LAST Q_TITLE DDR5 - CPU1 CHJ
J 0
(-9366 26);
DISPLAY 2.446809 (-9366 26);
PAINT GREEN (-9366 26);
FORCEPROP 1 LAST Q_DEPT BU9
J 1
(-3763 49);
DISPLAY 1.957447 (-3763 49);
PAINT GREEN (-3763 49);
FORCEPROP 2 LAST PAGE_BORDER TRUE
J 0
(-7890 5250);
DISPLAY 0.638298 (-7890 5250);
PAINT PINK (-7890 5250);
DISPLAY INVISIBLE (-7890 5250);
FORCEPROP 1 LAST CDS_LMAN_SYM_OUTLINE -9475,6775,100,-125
J 0
(0 0);
DISPLAY 0.468085 (0 0);
PAINT GREEN (0 0);
DISPLAY INVISIBLE (0 0);
FORCEPROP 2 LAST CDS_LIB pure_quanta
J 0
(0 0);
DISPLAY INVISIBLE (0 0);
FORCEPROP 1 LAST COMMENT_BODY TRUE
J 0
(12 -13);
DISPLAY 0.978723 (12 -13);
PAINT GREEN (12 -13);
DISPLAY INVISIBLE (12 -13);
FORCEPROP 2 LAST CDS_XR_PAGE_TITLE CR-106 : @T6G_MB_LIB.T6G(SCH_1):PAGE106
J 0
(-7890 5250);
DISPLAY 0.638298 (-7890 5250);
PAINT PINK (-7890 5250);
DISPLAY INVISIBLE (-7890 5250);
WIRE 17 -1 (-5800 3050)(-5800 3000);
WIRE 17 -1 (-5800 3100)(-5800 3050);
WIRE 17 -1 (-5800 3000)(-5800 2950);
WIRE 17 -1 (-5800 2900)(-5800 2950);
WIRE 17 -1 (-5800 3150)(-5800 3100);
WIRE 17 -1 (-5800 3200)(-5800 3150);
WIRE 17 -1 (-5800 2850)(-5800 2900);
WIRE 17 -1 (-5800 2800)(-5800 2850);
WIRE 17 -1 (-5800 3250)(-5800 3200);
WIRE 17 -1 (-5800 3300)(-5800 3250);
WIRE 17 -1 (-5800 2750)(-5800 2800);
WIRE 17 -1 (-5800 2750)(-5800 2700);
WIRE 17 -1 (-5800 3350)(-5800 3300);
WIRE 17 -1 (-5800 3400)(-5800 3350);
WIRE 17 -1 (-5800 2700)(-5800 2650);
WIRE 17 -1 (-5800 2650)(-5800 2600);
WIRE 17 -1 (-5800 3450)(-5800 3400);
WIRE 17 -1 (-5800 3500)(-5800 3450);
WIRE 17 -1 (-5800 2600)(-5800 2550);
WIRE 17 -1 (-5800 2550)(-5800 2500);
WIRE 17 -1 (-5800 3550)(-5800 3500);
WIRE 17 -1 (-5800 3600)(-5800 3550);
WIRE 17 -1 (-5800 2500)(-5800 2450);
WIRE 17 -1 (-5800 2450)(-5800 2400);
WIRE 17 -1 (-5800 3650)(-5800 3600);
WIRE 17 -1 (-5800 3700)(-5800 3650);
WIRE 17 -1 (-5800 2400)(-5800 2350);
WIRE 17 -1 (-5800 2300)(-5800 2350);
WIRE 17 -1 (-5800 3725)(-5800 3700);
WIRE 17 -1 (-5800 3725)(-5250 3725);
FORCEPROP 2 LAST SIG_NAME M_J_CPU1_SB_DQ<31:0>
J 0
(-5735 3735);
DISPLAY 0.489362 (-5735 3735);
WIRE 17 -1 (-3300 4675)(-3300 4575);
WIRE 17 -1 (-3300 4700)(-3300 4675);
WIRE 17 -1 (-3300 4575)(-3300 4475);
WIRE 17 -1 (-3300 4475)(-3300 4375);
WIRE 17 -1 (-3300 4700)(-2400 4700);
FORCEPROP 2 LAST SIG_NAME M_J_CPU1_SA_DQS_DP<9:0>
J 0
(-3035 4710);
DISPLAY 0.489362 (-3035 4710);
WIRE 17 -1 (-3100 4625)(-3100 4525);
WIRE 17 -1 (-3100 4650)(-3100 4625);
WIRE 17 -1 (-3100 4525)(-3100 4425);
WIRE 17 -1 (-3100 4425)(-3100 4325);
WIRE 17 -1 (-3100 4650)(-2400 4650);
FORCEPROP 2 LAST SIG_NAME M_J_CPU1_SA_DQS_DN<9:0>
J 0
(-3035 4660);
DISPLAY 0.489362 (-3035 4660);
WIRE 17 -1 (-3300 3650)(-3300 3625);
WIRE 17 -1 (-3300 3650)(-2400 3650);
FORCEPROP 2 LAST SIG_NAME M_J_CPU1_SB_DQS_DP<9:0>
J 0
(-3035 3660);
DISPLAY 0.489362 (-3035 3660);
WIRE 17 -1 (-3100 3600)(-3100 3575);
WIRE 17 -1 (-3100 3600)(-2400 3600);
FORCEPROP 2 LAST SIG_NAME M_J_CPU1_SB_DQS_DN<9:0>
J 0
(-3035 3610);
DISPLAY 0.489362 (-3035 3610);
WIRE 17 -1 (-3300 4375)(-3300 4275);
WIRE 17 -1 (-3100 4325)(-3100 4225);
WIRE 17 -1 (-3100 3375)(-3100 3275);
WIRE 17 -1 (-3100 3475)(-3100 3375);
WIRE 17 -1 (-3100 3275)(-3100 3175);
WIRE 17 -1 (-3100 3075)(-3100 3175);
WIRE 17 -1 (-3100 3575)(-3100 3475);
WIRE 17 -1 (-3100 2975)(-3100 3075);
WIRE 17 -1 (-3100 2875)(-3100 2975);
WIRE 17 -1 (-3300 4175)(-3300 4275);
WIRE 17 -1 (-3300 4075)(-3300 4175);
WIRE 17 -1 (-3300 3975)(-3300 4075);
WIRE 17 -1 (-3300 3325)(-3300 3225);
WIRE 17 -1 (-3300 3425)(-3300 3325);
WIRE 17 -1 (-3300 3125)(-3300 3225);
WIRE 17 -1 (-3300 3025)(-3300 3125);
WIRE 17 -1 (-3300 3525)(-3300 3425);
WIRE 17 -1 (-3300 3625)(-3300 3525);
WIRE 17 -1 (-3300 2925)(-3300 3025);
WIRE 17 -1 (-3300 2925)(-3300 2825);
WIRE 17 -1 (-3100 2875)(-3100 2775);
WIRE 17 -1 (-3100 4125)(-3100 4225);
WIRE 17 -1 (-3100 4025)(-3100 4125);
WIRE 17 -1 (-3100 3925)(-3100 4025);
WIRE 17 -1 (-3100 3925)(-3100 3825);
WIRE 17 -1 (-3300 2825)(-3300 2725);
WIRE 17 -1 (-3100 2775)(-3100 2675);
WIRE 17 -1 (-3300 3975)(-3300 3875);
WIRE 17 -1 (-3300 3875)(-3300 3775);
WIRE 17 -1 (-3100 3825)(-3100 3725);
WIRE 17 -1 (-5800 4550)(-5800 4600);
WIRE 17 -1 (-5800 4500)(-5800 4550);
WIRE 17 -1 (-5800 4650)(-5800 4600);
WIRE 17 -1 (-5800 4700)(-5800 4650);
WIRE 17 -1 (-5800 4450)(-5800 4500);
WIRE 17 -1 (-5800 4400)(-5800 4450);
WIRE 17 -1 (-5800 4750)(-5800 4700);
WIRE 17 -1 (-5800 4800)(-5800 4750);
WIRE 17 -1 (-5800 4400)(-5800 4350);
WIRE 17 -1 (-5800 4350)(-5800 4300);
WIRE 17 -1 (-5800 4850)(-5800 4800);
WIRE 17 -1 (-5800 4900)(-5800 4850);
WIRE 17 -1 (-5800 4300)(-5800 4250);
WIRE 17 -1 (-5800 4250)(-5800 4200);
WIRE 17 -1 (-5800 4950)(-5800 4900);
WIRE 17 -1 (-5800 5000)(-5800 4950);
WIRE 17 -1 (-5800 4200)(-5800 4150);
WIRE 17 -1 (-5800 4150)(-5800 4100);
WIRE 17 -1 (-5800 5050)(-5800 5000);
WIRE 17 -1 (-5800 5100)(-5800 5050);
WIRE 17 -1 (-5800 4100)(-5800 4050);
WIRE 17 -1 (-5800 4050)(-5800 4000);
WIRE 17 -1 (-5800 5150)(-5800 5100);
WIRE 17 -1 (-5800 5200)(-5800 5150);
WIRE 17 -1 (-5800 3950)(-5800 4000);
WIRE 17 -1 (-5800 3900)(-5800 3950);
WIRE 17 -1 (-5800 5250)(-5800 5200);
WIRE 17 -1 (-5800 5300)(-5800 5250);
WIRE 17 -1 (-5800 3850)(-5800 3900);
WIRE 17 -1 (-5800 3800)(-5800 3850);
WIRE 17 -1 (-5800 5350)(-5800 5300);
WIRE 17 -1 (-5800 5375)(-5800 5350);
WIRE 17 -1 (-5800 5375)(-5250 5375);
FORCEPROP 2 LAST SIG_NAME M_J_CPU1_SA_DQ<31:0>
J 0
(-5735 5385);
DISPLAY 0.489362 (-5735 5385);
WIRE 17 -1 (-7600 5350)(-7600 5375);
WIRE 17 -1 (-7600 5300)(-7600 5350);
WIRE 17 -1 (-7600 5375)(-8100 5375);
FORCEPROP 2 LAST SIG_NAME M_J_CPU1_SA_CA<6:0>
J 0
(-8085 5385);
DISPLAY 0.489362 (-8085 5385);
WIRE 17 -1 (-7600 5250)(-7600 5300);
WIRE 17 -1 (-7600 5200)(-7600 5250);
WIRE 17 -1 (-7600 5150)(-7600 5200);
WIRE 17 -1 (-7600 5100)(-7600 5150);
WIRE 17 -1 (-7600 5050)(-7600 5100);
WIRE 17 -1 (-5800 2150)(-5800 2200);
WIRE 17 -1 (-5800 2200)(-5800 2250);
WIRE 17 -1 (-5800 2250)(-5800 2300);
WIRE 17 -1 (-7600 3150)(-7600 3200);
WIRE 17 -1 (-7600 3200)(-7600 3250);
WIRE 17 -1 (-7600 3250)(-7600 3300);
WIRE 17 -1 (-7600 3300)(-7600 3350);
WIRE 17 -1 (-7600 3400)(-7600 3350);
WIRE 17 -1 (-7600 3400)(-7600 3450);
WIRE 17 -1 (-7600 3500)(-7600 3450);
WIRE 17 -1 (-7600 3500)(-7600 3525);
WIRE 17 -1 (-7600 3525)(-8100 3525);
FORCEPROP 2 LAST SIG_NAME M_J_CPU1_SB_CB<7:0>
J 0
(-8050 3535);
DISPLAY 0.489362 (-8050 3535);
WIRE 17 -1 (-7600 3600)(-7600 3650);
WIRE 17 -1 (-7600 3650)(-7600 3700);
WIRE 17 -1 (-7600 3700)(-7600 3750);
WIRE 17 -1 (-7600 3750)(-7600 3800);
WIRE 17 -1 (-7600 3850)(-7600 3800);
WIRE 17 -1 (-7600 3850)(-7600 3900);
WIRE 17 -1 (-7600 3950)(-7600 3900);
WIRE 17 -1 (-7600 3950)(-7600 3975);
WIRE 17 -1 (-7600 3975)(-8100 3975);
FORCEPROP 2 LAST SIG_NAME M_J_CPU1_SA_CB<7:0>
J 0
(-8050 3985);
DISPLAY 0.489362 (-8050 3985);
WIRE 17 -1 (-7600 4950)(-7600 4975);
WIRE 17 -1 (-7600 4900)(-7600 4950);
WIRE 17 -1 (-7600 4975)(-8100 4975);
FORCEPROP 2 LAST SIG_NAME M_J_CPU1_SB_CA<6:0>
J 0
(-8085 4985);
DISPLAY 0.489362 (-8085 4985);
WIRE 17 -1 (-7600 4850)(-7600 4900);
WIRE 17 -1 (-7600 4800)(-7600 4850);
WIRE 17 -1 (-7600 4750)(-7600 4800);
WIRE 17 -1 (-7600 4700)(-7600 4750);
WIRE 17 -1 (-7600 4650)(-7600 4700);
WIRE 16 -1 (-6250 1000)(-6250 1075);
WIRE 16 -1 (-8525 2975)(-8525 3050);
WIRE 16 -1 (-8250 2325)(-8250 2350);
WIRE 16 -1 (-7700 2625)(-8125 2625);
FORCEPROP 2 LAST SIG_NAME I3C_SPD_DDRGL_CPU1_SCL
J 0
(-8185 2635);
DISPLAY 0.489362 (-8185 2635);
WIRE 16 -1 (-8025 2075)(-8250 2075);
WIRE 16 -1 (-8025 2075)(-8025 2475);
WIRE 16 -1 (-8250 2125)(-8250 2075);
WIRE 16 -1 (-8250 2075)(-8275 2075);
WIRE 16 -1 (-7300 2475)(-8025 2475);
FORCEPROP 2 LAST SIG_NAME PWRGD_CHJ_CPU1_DIMM
J 0
(-7910 2485);
DISPLAY 0.489362 (-7910 2485);
FORCEPROP 2 LASTPROP $XRERR UNIQUE?
J 0
(-8150 2485);
DISPLAY 0.638298 (-8150 2485);
PAINT MONO (-8150 2485);
DISPLAY INVISIBLE (-8150 2485);
WIRE 16 -1 (-7400 2725)(-7400 2625);
FORCEPROP 2 LAST SIG_NAME I3C_SPD_DDRJ_CPU1_SCL
J 0
(-7785 2735);
DISPLAY 0.446809 (-7785 2735);
FORCEPROP 2 LASTPROP $XRERR UNIQUE?
J 0
(-8025 2735);
DISPLAY 0.638298 (-8025 2735);
PAINT MONO (-8025 2735);
DISPLAY INVISIBLE (-8025 2735);
WIRE 16 -1 (-7300 2725)(-7400 2725);
WIRE 16 -1 (-7400 2625)(-7500 2625);
WIRE 16 -1 (-7300 2775)(-8100 2775);
FORCEPROP 2 LAST SIG_NAME I3C_SPD_DDRGL_CPU1_SDA
J 0
(-8110 2785);
DISPLAY 0.489362 (-8110 2785);
WIRE 16 -1 (-7300 2825)(-8100 2825);
FORCEPROP 2 LAST SIG_NAME PD_CHJ_CPU1_DIMM_SAA
J 0
(-8075 2835);
DISPLAY 0.489362 (-8075 2835);
WIRE 16 -1 (-7300 1925)(-8100 1925);
FORCEPROP 2 LAST SIG_NAME M_J_CPU1_SA_RSP<0>
J 0
(-8050 1935);
DISPLAY 0.489362 (-8050 1935);
WIRE 16 -1 (-7300 2075)(-7900 2075);
FORCEPROP 2 LAST SIG_NAME TP_CHJ_CPU1_DIMM_RFU_0
J 0
(-7910 2085);
DISPLAY 0.489362 (-7910 2085);
FORCEPROP 2 LASTPROP $XRERR UNIQUE?
J 0
(-8140 2075);
DISPLAY 0.638298 (-8140 2075);
PAINT MONO (-8140 2075);
DISPLAY INVISIBLE (-8140 2075);
WIRE 16 -1 (-7300 2125)(-7900 2125);
FORCEPROP 2 LAST SIG_NAME TP_CHJ_CPU1_DIMM_RFU_1
J 0
(-7910 2135);
DISPLAY 0.489362 (-7910 2135);
FORCEPROP 2 LASTPROP $XRERR UNIQUE?
J 0
(-8140 2125);
DISPLAY 0.638298 (-8140 2125);
PAINT MONO (-8140 2125);
DISPLAY INVISIBLE (-8140 2125);
WIRE 16 -1 (-7300 2225)(-7900 2225);
FORCEPROP 2 LAST SIG_NAME TP_CHJ_CPU1_DIMM_RFU_3
J 0
(-7910 2235);
DISPLAY 0.489362 (-7910 2235);
FORCEPROP 2 LASTPROP $XRERR UNIQUE?
J 0
(-8140 2225);
DISPLAY 0.638298 (-8140 2225);
PAINT MONO (-8140 2225);
DISPLAY INVISIBLE (-8140 2225);
WIRE 16 -1 (-7300 2275)(-7900 2275);
FORCEPROP 2 LAST SIG_NAME TP_CHJ_CPU1_DIMM_RFU_4
J 0
(-7910 2285);
DISPLAY 0.489362 (-7910 2285);
FORCEPROP 2 LASTPROP $XRERR UNIQUE?
J 0
(-8140 2275);
DISPLAY 0.638298 (-8140 2275);
PAINT MONO (-8140 2275);
DISPLAY INVISIBLE (-8140 2275);
WIRE 16 -1 (-7300 2325)(-7900 2325);
FORCEPROP 2 LAST SIG_NAME TP_CHJ_CPU1_DIMM_RFU_5
J 0
(-7910 2335);
DISPLAY 0.489362 (-7910 2335);
FORCEPROP 2 LASTPROP $XRERR UNIQUE?
J 0
(-8140 2325);
DISPLAY 0.638298 (-8140 2325);
PAINT MONO (-8140 2325);
DISPLAY INVISIBLE (-8140 2325);
WIRE 16 -1 (-7300 2375)(-7900 2375);
FORCEPROP 2 LAST SIG_NAME TP_CHJ_CPU1_DIMM_RFU_6
J 0
(-7910 2385);
DISPLAY 0.489362 (-7910 2385);
FORCEPROP 2 LASTPROP $XRERR UNIQUE?
J 0
(-8140 2375);
DISPLAY 0.638298 (-8140 2375);
PAINT MONO (-8140 2375);
DISPLAY INVISIBLE (-8140 2375);
WIRE 16 -1 (-6100 2675)(-5900 2675);
WIRE 16 -1 (-8425 2875)(-7300 2875);
WIRE 16 -1 (-8425 3275)(-8425 2875);
WIRE 16 -1 (-8425 3300)(-8425 3275);
WIRE 16 -1 (-8525 3275)(-8425 3275);
WIRE 16 -1 (-8525 3250)(-8525 3275);
WIRE 16 -1 (-7300 2975)(-7900 2975);
FORCEPROP 2 LAST SIG_NAME M_J_CPU1_ALERT_N
J 0
(-7885 2985);
DISPLAY 0.489362 (-7885 2985);
WIRE 16 -1 (-7300 3025)(-7900 3025);
FORCEPROP 2 LAST SIG_NAME M_J_CPU1_RESET_N
J 0
(-7885 3035);
DISPLAY 0.489362 (-7885 3035);
WIRE 16 -1 (-2150 5550)(-2725 5550);
WIRE 16 -1 (-2150 5550)(-2150 5675);
WIRE 16 -1 (-2725 5550)(-2725 5675);
WIRE 16 -1 (-2725 5550)(-2725 5475);
WIRE 16 -1 (-6250 1350)(-6250 1275);
WIRE 16 -1 (-6250 1350)(-6975 1350);
FORCEPROP 2 LAST SIG_NAME PD_CHJ_CPU1_DIMM_SAA
J 0
(-6960 1360);
DISPLAY 0.489362 (-6960 1360);
WIRE 16 -1 (-8475 2075)(-8875 2075);
FORCEPROP 2 LAST SIG_NAME PWRGD_CHGL_CPU1
J 0
(-8835 2085);
DISPLAY 0.489362 (-8835 2085);
WIRE 16 -1 (-6100 5325)(-5900 5325);
WIRE 16 -1 (-7300 3925)(-7500 3925);
WIRE 16 -1 (-7300 3775)(-7500 3775);
WIRE 16 -1 (-7300 3625)(-7500 3625);
WIRE 16 -1 (-7300 3475)(-7500 3475);
WIRE 16 -1 (-7300 5025)(-7500 5025);
WIRE 16 -1 (-7300 4625)(-7500 4625);
WIRE 16 -1 (-7300 5075)(-7500 5075);
WIRE 16 -1 (-7300 4675)(-7500 4675);
WIRE 16 -1 (-7300 5125)(-7500 5125);
WIRE 16 -1 (-7300 4725)(-7500 4725);
WIRE 16 -1 (-7300 4775)(-7500 4775);
WIRE 16 -1 (-7300 5225)(-7500 5225);
WIRE 16 -1 (-7300 4825)(-7500 4825);
WIRE 16 -1 (-7300 4875)(-7500 4875);
WIRE 16 -1 (-7300 4925)(-7500 4925);
WIRE 16 -1 (-7300 3875)(-7500 3875);
WIRE 16 -1 (-7300 3825)(-7500 3825);
WIRE 16 -1 (-7300 3725)(-7500 3725);
WIRE 16 -1 (-7300 3675)(-7500 3675);
WIRE 16 -1 (-7300 3575)(-7500 3575);
WIRE 16 -1 (-7300 3425)(-7500 3425);
WIRE 16 -1 (-7300 3375)(-7500 3375);
WIRE 16 -1 (-7300 3325)(-7500 3325);
WIRE 16 -1 (-7300 3275)(-7500 3275);
WIRE 16 -1 (-7300 3225)(-7500 3225);
WIRE 16 -1 (-7300 3175)(-7500 3175);
WIRE 16 -1 (-7300 3125)(-7500 3125);
WIRE 16 -1 (-7300 4025)(-8100 4025);
FORCEPROP 2 LAST SIG_NAME M_J_CPU1_CLK_DN<0>
J 0
(-8050 4035);
DISPLAY 0.489362 (-8050 4035);
WIRE 16 -1 (-7300 4075)(-8100 4075);
FORCEPROP 2 LAST SIG_NAME M_J_CPU1_CLK_DP<0>
J 0
(-8050 4085);
DISPLAY 0.489362 (-8050 4085);
WIRE 16 -1 (-7300 4175)(-8100 4175);
FORCEPROP 2 LAST SIG_NAME M_J_CPU1_SB_CS_N<0>
J 0
(-8050 4185);
DISPLAY 0.489362 (-8050 4185);
WIRE 16 -1 (-7300 4375)(-8100 4375);
FORCEPROP 2 LAST SIG_NAME M_J_CPU1_SA_CS_N<1>
J 0
(-8050 4385);
DISPLAY 0.489362 (-8050 4385);
WIRE 16 -1 (-7300 4225)(-8100 4225);
FORCEPROP 2 LAST SIG_NAME M_J_CPU1_SB_CS_N<1>
J 0
(-8050 4235);
DISPLAY 0.489362 (-8050 4235);
WIRE 16 -1 (-5900 5275)(-6100 5275);
WIRE 16 -1 (-5900 5175)(-6100 5175);
WIRE 16 -1 (-6100 5125)(-5900 5125);
WIRE 16 -1 (-5900 5075)(-6100 5075);
WIRE 16 -1 (-5900 5025)(-6100 5025);
WIRE 16 -1 (-5900 4775)(-6100 4775);
WIRE 16 -1 (-6100 4725)(-5900 4725);
WIRE 16 -1 (-5900 4675)(-6100 4675);
WIRE 16 -1 (-5900 4625)(-6100 4625);
WIRE 16 -1 (-5900 4575)(-6100 4575);
WIRE 16 -1 (-5900 4475)(-6100 4475);
WIRE 16 -1 (-5900 4425)(-6100 4425);
WIRE 16 -1 (-5900 4375)(-6100 4375);
WIRE 16 -1 (-6100 4325)(-5900 4325);
WIRE 16 -1 (-5900 4275)(-6100 4275);
WIRE 16 -1 (-5900 4225)(-6100 4225);
WIRE 16 -1 (-5900 4175)(-6100 4175);
WIRE 16 -1 (-6100 4125)(-5900 4125);
WIRE 16 -1 (-5900 4075)(-6100 4075);
WIRE 16 -1 (-5900 4025)(-6100 4025);
WIRE 16 -1 (-5900 3975)(-6100 3975);
WIRE 16 -1 (-6100 3925)(-5900 3925);
WIRE 16 -1 (-5900 3875)(-6100 3875);
WIRE 16 -1 (-5900 3825)(-6100 3825);
WIRE 16 -1 (-5900 3775)(-6100 3775);
WIRE 16 -1 (-6100 3675)(-5900 3675);
WIRE 16 -1 (-5900 3625)(-6100 3625);
WIRE 16 -1 (-5900 3575)(-6100 3575);
WIRE 16 -1 (-5900 3525)(-6100 3525);
WIRE 16 -1 (-6100 3475)(-5900 3475);
WIRE 16 -1 (-5900 3425)(-6100 3425);
WIRE 16 -1 (-5900 3375)(-6100 3375);
WIRE 16 -1 (-5900 3325)(-6100 3325);
WIRE 16 -1 (-6100 3275)(-5900 3275);
WIRE 16 -1 (-5900 3225)(-6100 3225);
WIRE 16 -1 (-5900 3175)(-6100 3175);
WIRE 16 -1 (-6100 3075)(-5900 3075);
WIRE 16 -1 (-5900 2975)(-6100 2975);
WIRE 16 -1 (-5900 2925)(-6100 2925);
WIRE 16 -1 (-6100 2875)(-5900 2875);
WIRE 16 -1 (-5900 2825)(-6100 2825);
WIRE 16 -1 (-5900 2775)(-6100 2775);
WIRE 16 -1 (-5900 2725)(-6100 2725);
WIRE 16 -1 (-5900 2625)(-6100 2625);
WIRE 16 -1 (-5900 2575)(-6100 2575);
WIRE 16 -1 (-5900 2525)(-6100 2525);
WIRE 16 -1 (-6100 2475)(-5900 2475);
WIRE 16 -1 (-5900 2425)(-6100 2425);
WIRE 16 -1 (-5900 2375)(-6100 2375);
WIRE 16 -1 (-5900 2325)(-6100 2325);
WIRE 16 -1 (-6100 2275)(-5900 2275);
WIRE 16 -1 (-5900 2225)(-6100 2225);
WIRE 16 -1 (-5900 2175)(-6100 2175);
WIRE 16 -1 (-5900 2125)(-6100 2125);
WIRE 16 -1 (-7300 1875)(-8100 1875);
FORCEPROP 2 LAST SIG_NAME M_J_CPU1_SB_RSP<0>
J 0
(-8050 1885);
DISPLAY 0.489362 (-8050 1885);
WIRE 16 -1 (-7300 4525)(-8100 4525);
FORCEPROP 2 LAST SIG_NAME M_J_CPU1_SA_PAR
J 0
(-8050 4535);
DISPLAY 0.489362 (-8050 4535);
WIRE 16 -1 (-7300 4475)(-8100 4475);
FORCEPROP 2 LAST SIG_NAME M_J_CPU1_SB_PAR
J 0
(-8050 4485);
DISPLAY 0.489362 (-8050 4485);
WIRE 16 -1 (-5900 5225)(-6100 5225);
WIRE 16 -1 (-5900 4825)(-6100 4825);
WIRE 16 -1 (-5900 4875)(-6100 4875);
WIRE 16 -1 (-7300 5175)(-7500 5175);
WIRE 16 -1 (-7300 5275)(-7500 5275);
WIRE 16 -1 (-7300 5325)(-7500 5325);
WIRE 16 -1 (-5900 4975)(-6100 4975);
WIRE 16 -1 (-6100 4925)(-5900 4925);
WIRE 16 -1 (-6100 4525)(-5900 4525);
WIRE 16 -1 (-3550 4400)(-3200 4400);
WIRE 16 -1 (-3400 4350)(-3550 4350);
WIRE 16 -1 (-3400 3500)(-3550 3500);
WIRE 16 -1 (-3550 3450)(-3200 3450);
WIRE 16 -1 (-3400 3400)(-3550 3400);
WIRE 16 -1 (-3550 3700)(-3200 3700);
WIRE 16 -1 (-3400 3750)(-3550 3750);
WIRE 16 -1 (-3550 2650)(-3200 2650);
WIRE 16 -1 (-3400 2700)(-3550 2700);
WIRE 16 -1 (-3550 3800)(-3200 3800);
WIRE 16 -1 (-3550 3850)(-3400 3850);
WIRE 16 -1 (-3550 2750)(-3200 2750);
WIRE 16 -1 (-3550 2800)(-3400 2800);
WIRE 16 -1 (-3550 3900)(-3200 3900);
WIRE 16 -1 (-3400 3950)(-3550 3950);
WIRE 16 -1 (-3550 2850)(-3200 2850);
WIRE 16 -1 (-3400 2900)(-3550 2900);
WIRE 16 -1 (-3550 4000)(-3200 4000);
WIRE 16 -1 (-3400 4050)(-3550 4050);
WIRE 16 -1 (-3550 2950)(-3200 2950);
WIRE 16 -1 (-3400 3000)(-3550 3000);
WIRE 16 -1 (-3550 4100)(-3200 4100);
WIRE 16 -1 (-3400 4150)(-3550 4150);
WIRE 16 -1 (-3550 3050)(-3200 3050);
WIRE 16 -1 (-3400 3100)(-3550 3100);
WIRE 16 -1 (-3550 4200)(-3200 4200);
WIRE 16 -1 (-3550 4250)(-3400 4250);
WIRE 16 -1 (-3550 3150)(-3200 3150);
WIRE 16 -1 (-3550 3200)(-3400 3200);
WIRE 16 -1 (-3550 4300)(-3200 4300);
WIRE 16 -1 (-3550 3250)(-3200 3250);
WIRE 16 -1 (-3400 3300)(-3550 3300);
WIRE 16 -1 (-3400 4450)(-3550 4450);
WIRE 16 -1 (-3550 3350)(-3200 3350);
WIRE 16 -1 (-3550 4500)(-3200 4500);
WIRE 16 -1 (-3400 4550)(-3550 4550);
WIRE 16 -1 (-3550 3550)(-3200 3550);
WIRE 16 -1 (-3550 3600)(-3400 3600);
WIRE 16 -1 (-3550 4600)(-3200 4600);
WIRE 16 -1 (-3550 4650)(-3400 4650);
WIRE 16 -1 (-2025 5125)(-1725 5125);
WIRE 16 -1 (-2025 5175)(-2025 5125);
WIRE 16 -1 (-1725 5175)(-2025 5175);
WIRE 16 -1 (-2025 5175)(-2025 5225);
WIRE 16 -1 (-2025 5225)(-2025 5975);
WIRE 16 -1 (-1725 5225)(-2025 5225);
WIRE 16 -1 (-2150 5975)(-2025 5975);
WIRE 16 -1 (-2150 5975)(-2725 5975);
WIRE 16 -1 (-2150 5975)(-2150 5875);
WIRE 16 -1 (-2725 5975)(-2725 6050);
WIRE 16 -1 (-2725 5875)(-2725 5975);
WIRE 16 -1 (-225 1925)(-225 1875);
WIRE 16 -1 (-225 1975)(-225 1925);
WIRE 16 -1 (-225 1925)(-525 1925);
WIRE 16 -1 (-225 1875)(-225 1625);
WIRE 16 -1 (-225 1875)(-525 1875);
WIRE 16 -1 (-225 2075)(-225 1975);
WIRE 16 -1 (-225 1975)(-525 1975);
WIRE 16 -1 (-225 2125)(-225 2075);
WIRE 16 -1 (-225 2075)(-525 2075);
WIRE 16 -1 (-225 2175)(-225 2125);
WIRE 16 -1 (-225 2125)(-525 2125);
WIRE 16 -1 (-225 2225)(-225 2175);
WIRE 16 -1 (-225 2175)(-525 2175);
WIRE 16 -1 (-225 2275)(-225 2225);
WIRE 16 -1 (-225 2225)(-525 2225);
WIRE 16 -1 (-225 2325)(-225 2275);
WIRE 16 -1 (-225 2275)(-525 2275);
WIRE 16 -1 (-225 2375)(-225 2325);
WIRE 16 -1 (-225 2325)(-525 2325);
WIRE 16 -1 (-225 2425)(-225 2375);
WIRE 16 -1 (-225 2375)(-525 2375);
WIRE 16 -1 (-225 2475)(-225 2425);
WIRE 16 -1 (-225 2425)(-525 2425);
WIRE 16 -1 (-225 2525)(-225 2475);
WIRE 16 -1 (-225 2475)(-525 2475);
WIRE 16 -1 (-225 2575)(-225 2525);
WIRE 16 -1 (-225 2525)(-525 2525);
WIRE 16 -1 (-225 2625)(-225 2575);
WIRE 16 -1 (-225 2575)(-525 2575);
WIRE 16 -1 (-225 2675)(-225 2625);
WIRE 16 -1 (-225 2625)(-525 2625);
WIRE 16 -1 (-225 2725)(-225 2675);
WIRE 16 -1 (-225 2675)(-525 2675);
WIRE 16 -1 (-225 2775)(-225 2725);
WIRE 16 -1 (-225 2725)(-525 2725);
WIRE 16 -1 (-225 2825)(-225 2775);
WIRE 16 -1 (-225 2775)(-525 2775);
WIRE 16 -1 (-225 2875)(-225 2825);
WIRE 16 -1 (-225 2825)(-525 2825);
WIRE 16 -1 (-225 2925)(-225 2875);
WIRE 16 -1 (-225 2875)(-525 2875);
WIRE 16 -1 (-225 2975)(-225 2925);
WIRE 16 -1 (-225 2925)(-525 2925);
WIRE 16 -1 (-225 3025)(-225 2975);
WIRE 16 -1 (-225 2975)(-525 2975);
WIRE 16 -1 (-225 3075)(-225 3025);
WIRE 16 -1 (-225 3025)(-525 3025);
WIRE 16 -1 (-225 3125)(-225 3075);
WIRE 16 -1 (-225 3075)(-525 3075);
WIRE 16 -1 (-225 3175)(-225 3125);
WIRE 16 -1 (-225 3125)(-525 3125);
WIRE 16 -1 (-225 3225)(-225 3175);
WIRE 16 -1 (-225 3175)(-525 3175);
WIRE 16 -1 (-225 3275)(-225 3225);
WIRE 16 -1 (-225 3225)(-525 3225);
WIRE 16 -1 (-225 3325)(-225 3275);
WIRE 16 -1 (-225 3275)(-525 3275);
WIRE 16 -1 (-225 3375)(-225 3325);
WIRE 16 -1 (-225 3325)(-525 3325);
WIRE 16 -1 (-225 3425)(-225 3375);
WIRE 16 -1 (-225 3375)(-525 3375);
WIRE 16 -1 (-225 3475)(-225 3425);
WIRE 16 -1 (-225 3425)(-525 3425);
WIRE 16 -1 (-225 3525)(-225 3475);
WIRE 16 -1 (-225 3475)(-525 3475);
WIRE 16 -1 (-225 3575)(-225 3525);
WIRE 16 -1 (-225 3525)(-525 3525);
WIRE 16 -1 (-225 3625)(-225 3575);
WIRE 16 -1 (-225 3575)(-525 3575);
WIRE 16 -1 (-225 3675)(-225 3625);
WIRE 16 -1 (-225 3625)(-525 3625);
WIRE 16 -1 (-225 3725)(-225 3675);
WIRE 16 -1 (-225 3675)(-525 3675);
WIRE 16 -1 (-225 3775)(-225 3725);
WIRE 16 -1 (-225 3725)(-525 3725);
WIRE 16 -1 (-225 3825)(-225 3775);
WIRE 16 -1 (-225 3775)(-525 3775);
WIRE 16 -1 (-225 3875)(-225 3825);
WIRE 16 -1 (-225 3825)(-525 3825);
WIRE 16 -1 (-225 3925)(-225 3875);
WIRE 16 -1 (-225 3875)(-525 3875);
WIRE 16 -1 (-225 3975)(-225 3925);
WIRE 16 -1 (-225 3925)(-525 3925);
WIRE 16 -1 (-225 4025)(-225 3975);
WIRE 16 -1 (-225 3975)(-525 3975);
WIRE 16 -1 (-225 4075)(-225 4025);
WIRE 16 -1 (-225 4025)(-525 4025);
WIRE 16 -1 (-225 4125)(-225 4075);
WIRE 16 -1 (-225 4075)(-525 4075);
WIRE 16 -1 (-225 4175)(-225 4125);
WIRE 16 -1 (-225 4125)(-525 4125);
WIRE 16 -1 (-225 4225)(-225 4175);
WIRE 16 -1 (-225 4175)(-525 4175);
WIRE 16 -1 (-225 4275)(-225 4225);
WIRE 16 -1 (-225 4225)(-525 4225);
WIRE 16 -1 (-225 4325)(-225 4275);
WIRE 16 -1 (-225 4275)(-525 4275);
WIRE 16 -1 (-225 4375)(-225 4325);
WIRE 16 -1 (-225 4325)(-525 4325);
WIRE 16 -1 (-225 4425)(-225 4375);
WIRE 16 -1 (-225 4375)(-525 4375);
WIRE 16 -1 (-225 4475)(-225 4425);
WIRE 16 -1 (-225 4425)(-525 4425);
WIRE 16 -1 (-225 4525)(-225 4475);
WIRE 16 -1 (-225 4475)(-525 4475);
WIRE 16 -1 (-225 4575)(-225 4525);
WIRE 16 -1 (-225 4525)(-525 4525);
WIRE 16 -1 (-225 4625)(-225 4575);
WIRE 16 -1 (-225 4575)(-525 4575);
WIRE 16 -1 (-225 4675)(-225 4625);
WIRE 16 -1 (-225 4625)(-525 4625);
WIRE 16 -1 (-225 4725)(-225 4675);
WIRE 16 -1 (-225 4675)(-525 4675);
WIRE 16 -1 (-225 4775)(-225 4725);
WIRE 16 -1 (-225 4725)(-525 4725);
WIRE 16 -1 (-225 4825)(-225 4775);
WIRE 16 -1 (-225 4775)(-525 4775);
WIRE 16 -1 (-225 4875)(-225 4825);
WIRE 16 -1 (-225 4825)(-525 4825);
WIRE 16 -1 (-225 4925)(-225 4875);
WIRE 16 -1 (-225 4875)(-525 4875);
WIRE 16 -1 (-225 4975)(-225 4925);
WIRE 16 -1 (-225 4925)(-525 4925);
WIRE 16 -1 (-225 5025)(-225 4975);
WIRE 16 -1 (-225 4975)(-525 4975);
WIRE 16 -1 (-225 5075)(-225 5025);
WIRE 16 -1 (-225 5025)(-525 5025);
WIRE 16 -1 (-225 5125)(-225 5075);
WIRE 16 -1 (-225 5075)(-525 5075);
WIRE 16 -1 (-225 5175)(-225 5125);
WIRE 16 -1 (-225 5125)(-525 5125);
WIRE 16 -1 (-225 5225)(-225 5175);
WIRE 16 -1 (-225 5175)(-525 5175);
WIRE 16 -1 (-225 5225)(-525 5225);
WIRE 16 -1 (-1725 5075)(-2025 5075);
WIRE 16 -1 (-2025 5075)(-2025 5025);
WIRE 16 -1 (-1725 5025)(-2025 5025);
WIRE 16 -1 (-2025 5025)(-2025 4975);
WIRE 16 -1 (-1725 4975)(-2025 4975);
WIRE 16 -1 (-2025 4975)(-2025 4925);
WIRE 16 -1 (-1725 4925)(-2025 4925);
WIRE 16 -1 (-2025 4925)(-2025 4875);
WIRE 16 -1 (-1725 4875)(-2025 4875);
WIRE 16 -1 (-2025 4875)(-2025 4825);
WIRE 16 -1 (-1725 4825)(-2025 4825);
WIRE 16 -1 (-2025 4825)(-2025 4775);
WIRE 16 -1 (-1725 4775)(-2025 4775);
WIRE 16 -1 (-2025 4775)(-2025 4725);
WIRE 16 -1 (-1725 4725)(-2025 4725);
WIRE 16 -1 (-2025 4725)(-2025 4675);
WIRE 16 -1 (-1725 4675)(-2025 4675);
WIRE 16 -1 (-2025 4675)(-2025 4625);
WIRE 16 -1 (-1725 4625)(-2025 4625);
WIRE 16 -1 (-2025 4625)(-2025 4575);
WIRE 16 -1 (-1725 4575)(-2025 4575);
WIRE 16 -1 (-2025 4575)(-2025 4525);
WIRE 16 -1 (-1725 4525)(-2025 4525);
WIRE 16 -1 (-2025 4525)(-2025 4475);
WIRE 16 -1 (-1725 4475)(-2025 4475);
WIRE 16 -1 (-2025 4475)(-2025 4425);
WIRE 16 -1 (-1725 4425)(-2025 4425);
WIRE 16 -1 (-2025 4425)(-2025 4375);
WIRE 16 -1 (-1725 4375)(-2025 4375);
WIRE 16 -1 (-2025 4375)(-2025 4325);
WIRE 16 -1 (-1725 4325)(-2025 4325);
WIRE 16 -1 (-2025 4325)(-2025 4275);
WIRE 16 -1 (-1725 4275)(-2025 4275);
WIRE 16 -1 (-2025 4275)(-2025 4225);
WIRE 16 -1 (-1725 4225)(-2025 4225);
WIRE 16 -1 (-2025 4225)(-2025 4175);
WIRE 16 -1 (-1725 4175)(-2025 4175);
WIRE 16 -1 (-2025 4175)(-2025 4125);
WIRE 16 -1 (-1725 4125)(-2025 4125);
WIRE 16 -1 (-2025 4125)(-2025 4075);
WIRE 16 -1 (-1725 4075)(-2025 4075);
WIRE 16 -1 (-2025 4075)(-2025 4025);
WIRE 16 -1 (-1725 4025)(-2025 4025);
WIRE 16 -1 (-2025 4025)(-2025 3975);
WIRE 16 -1 (-1725 3975)(-2025 3975);
WIRE 16 -1 (-2025 3975)(-2025 3925);
WIRE 16 -1 (-1725 3925)(-2025 3925);
WIRE 16 -1 (-2025 3925)(-2025 3875);
WIRE 16 -1 (-1725 3875)(-2025 3875);
WIRE 16 -1 (-2025 3875)(-2025 3825);
WIRE 16 -1 (-1725 3825)(-2025 3825);
WIRE 16 -1 (-2025 3825)(-2025 3775);
WIRE 16 -1 (-1725 3775)(-2025 3775);
WIRE 16 -1 (-2025 3775)(-2025 3725);
WIRE 16 -1 (-1725 3725)(-2025 3725);
WIRE 16 -1 (-2025 3725)(-2025 3675);
WIRE 16 -1 (-1725 3675)(-2025 3675);
WIRE 16 -1 (-2025 3675)(-2025 3625);
WIRE 16 -1 (-1725 3625)(-2025 3625);
WIRE 16 -1 (-2025 3625)(-2025 3575);
WIRE 16 -1 (-1725 3575)(-2025 3575);
WIRE 16 -1 (-2025 3575)(-2025 3525);
WIRE 16 -1 (-1725 3525)(-2025 3525);
WIRE 16 -1 (-2025 3525)(-2025 3475);
WIRE 16 -1 (-1725 3475)(-2025 3475);
WIRE 16 -1 (-2025 3475)(-2025 3425);
WIRE 16 -1 (-1725 3425)(-2025 3425);
WIRE 16 -1 (-2025 3425)(-2025 3375);
WIRE 16 -1 (-1725 3375)(-2025 3375);
WIRE 16 -1 (-2025 3375)(-2025 3325);
WIRE 16 -1 (-1725 3325)(-2025 3325);
WIRE 16 -1 (-2025 3325)(-2025 3275);
WIRE 16 -1 (-1725 3275)(-2025 3275);
WIRE 16 -1 (-2025 3275)(-2025 3225);
WIRE 16 -1 (-1725 3225)(-2025 3225);
WIRE 16 -1 (-2025 3225)(-2025 3175);
WIRE 16 -1 (-1725 3175)(-2025 3175);
WIRE 16 -1 (-2025 3175)(-2025 3125);
WIRE 16 -1 (-1725 3125)(-2025 3125);
WIRE 16 -1 (-2025 3125)(-2025 3075);
WIRE 16 -1 (-1725 3075)(-2025 3075);
WIRE 16 -1 (-2025 3075)(-2025 3025);
WIRE 16 -1 (-1725 3025)(-2025 3025);
WIRE 16 -1 (-2025 3025)(-2025 2975);
WIRE 16 -1 (-1725 2975)(-2025 2975);
WIRE 16 -1 (-2025 2975)(-2025 2925);
WIRE 16 -1 (-1725 2925)(-2025 2925);
WIRE 16 -1 (-2025 2925)(-2025 2875);
WIRE 16 -1 (-1725 2875)(-2025 2875);
WIRE 16 -1 (-2025 2875)(-2025 2825);
WIRE 16 -1 (-1725 2825)(-2025 2825);
WIRE 16 -1 (-2025 2825)(-2025 2775);
WIRE 16 -1 (-1725 2775)(-2025 2775);
WIRE 16 -1 (-2025 2775)(-2025 2725);
WIRE 16 -1 (-1725 2725)(-2025 2725);
WIRE 16 -1 (-2025 2725)(-2025 2675);
WIRE 16 -1 (-1725 2675)(-2025 2675);
WIRE 16 -1 (-2025 2675)(-2025 2625);
WIRE 16 -1 (-1725 2625)(-2025 2625);
WIRE 16 -1 (-2025 2625)(-2025 2575);
WIRE 16 -1 (-1725 2575)(-2025 2575);
WIRE 16 -1 (-2025 2575)(-2025 2525);
WIRE 16 -1 (-1725 2525)(-2025 2525);
WIRE 16 -1 (-2025 2525)(-2025 2475);
WIRE 16 -1 (-1725 2475)(-2025 2475);
WIRE 16 -1 (-2025 2475)(-2025 2425);
WIRE 16 -1 (-1725 2425)(-2025 2425);
WIRE 16 -1 (-2025 2425)(-2025 2375);
WIRE 16 -1 (-1725 2375)(-2025 2375);
WIRE 16 -1 (-2025 2375)(-2025 2325);
WIRE 16 -1 (-1725 2325)(-2025 2325);
WIRE 16 -1 (-2025 2325)(-2025 2275);
WIRE 16 -1 (-1725 2275)(-2025 2275);
WIRE 16 -1 (-2025 2275)(-2025 2225);
WIRE 16 -1 (-1725 2225)(-2025 2225);
WIRE 16 -1 (-2025 2225)(-2025 2175);
WIRE 16 -1 (-1725 2175)(-2025 2175);
WIRE 16 -1 (-2025 2175)(-2025 2125);
WIRE 16 -1 (-1725 2125)(-2025 2125);
WIRE 16 -1 (-2025 2125)(-2025 2075);
WIRE 16 -1 (-1725 2075)(-2025 2075);
WIRE 16 -1 (-2025 2075)(-2025 2025);
WIRE 16 -1 (-2025 2025)(-2025 1975);
WIRE 16 -1 (-1725 2025)(-2025 2025);
WIRE 16 -1 (-1725 1975)(-2025 1975);
WIRE 16 -1 (-2025 1975)(-2025 1850);
WIRE 16 -1 (-7300 4325)(-8100 4325);
FORCEPROP 2 LAST SIG_NAME M_J_CPU1_SA_CS_N<0>
J 0
(-8050 4335);
DISPLAY 0.489362 (-8050 4335);
WIRE 16 -1 (-5900 3125)(-6100 3125);
WIRE 16 -1 (-5900 3025)(-6100 3025);
WIRE 16 -1 (-7300 2175)(-7900 2175);
FORCEPROP 2 LAST SIG_NAME TP_CHJ_CPU1_DIMM_RFU_2
J 0
(-7910 2185);
DISPLAY 0.489362 (-7910 2185);
FORCEPROP 2 LASTPROP $XRERR UNIQUE?
J 0
(-8140 2175);
DISPLAY 0.638298 (-8140 2175);
PAINT MONO (-8140 2175);
DISPLAY INVISIBLE (-8140 2175);
DOT 1 (-2150 5975);
DOT 1 (-2725 5975);
DOT 1 (-2725 5550);
DOT 1 (-8250 2075);
DOT 1 (-8425 3275);
DOT 1 (-2025 2025);
DOT 1 (-2025 1975);
DOT 1 (-2025 2125);
DOT 1 (-2025 2075);
DOT 1 (-2025 2175);
DOT 1 (-2025 2275);
DOT 1 (-2025 2225);
DOT 1 (-2025 2375);
DOT 1 (-2025 2325);
DOT 1 (-2025 2425);
DOT 1 (-2025 2525);
DOT 1 (-2025 2475);
DOT 1 (-2025 2575);
DOT 1 (-2025 2625);
DOT 1 (-2025 2675);
DOT 1 (-2025 2775);
DOT 1 (-2025 2725);
DOT 1 (-2025 2825);
DOT 1 (-2025 2925);
DOT 1 (-2025 2875);
DOT 1 (-2025 3025);
DOT 1 (-2025 2975);
DOT 1 (-2025 3075);
DOT 1 (-2025 3175);
DOT 1 (-2025 3125);
DOT 1 (-2025 3275);
DOT 1 (-2025 3225);
DOT 1 (-2025 3325);
DOT 1 (-2025 3425);
DOT 1 (-2025 3375);
DOT 1 (-2025 3475);
DOT 1 (-2025 3525);
DOT 1 (-2025 3575);
DOT 1 (-2025 3675);
DOT 1 (-2025 3625);
DOT 1 (-225 1925);
DOT 1 (-225 1875);
DOT 1 (-225 1975);
DOT 1 (-225 2125);
DOT 1 (-225 2075);
DOT 1 (-225 2175);
DOT 1 (-225 2275);
DOT 1 (-225 2225);
DOT 1 (-225 2375);
DOT 1 (-225 2425);
DOT 1 (-225 2325);
DOT 1 (-225 2525);
DOT 1 (-225 2475);
DOT 1 (-225 2575);
DOT 1 (-225 2625);
DOT 1 (-225 2675);
DOT 1 (-225 2775);
DOT 1 (-225 2725);
DOT 1 (-225 2825);
DOT 1 (-225 2925);
DOT 1 (-225 2875);
DOT 1 (-225 3025);
DOT 1 (-225 3075);
DOT 1 (-225 2975);
DOT 1 (-225 3175);
DOT 1 (-225 3125);
DOT 1 (-225 3275);
DOT 1 (-225 3325);
DOT 1 (-225 3225);
DOT 1 (-225 3425);
DOT 1 (-225 3375);
DOT 1 (-225 3475);
DOT 1 (-225 3575);
DOT 1 (-225 3525);
DOT 1 (-225 3675);
DOT 1 (-225 3625);
DOT 1 (-2025 3725);
DOT 1 (-2025 3775);
DOT 1 (-2025 3825);
DOT 1 (-2025 3875);
DOT 1 (-2025 3925);
DOT 1 (-2025 3975);
DOT 1 (-2025 4075);
DOT 1 (-2025 4025);
DOT 1 (-2025 4175);
DOT 1 (-2025 4125);
DOT 1 (-2025 4225);
DOT 1 (-2025 4275);
DOT 1 (-2025 4325);
DOT 1 (-2025 4425);
DOT 1 (-2025 4375);
DOT 1 (-2025 4475);
DOT 1 (-2025 4575);
DOT 1 (-2025 4525);
DOT 1 (-2025 4625);
DOT 1 (-2025 4675);
DOT 1 (-2025 4725);
DOT 1 (-2025 4825);
DOT 1 (-2025 4775);
DOT 1 (-2025 4875);
DOT 1 (-2025 5025);
DOT 1 (-2025 5225);
DOT 1 (-2025 5175);
DOT 1 (-225 3725);
DOT 1 (-225 3825);
DOT 1 (-225 3775);
DOT 1 (-225 3925);
DOT 1 (-225 3875);
DOT 1 (-225 3975);
DOT 1 (-225 4075);
DOT 1 (-225 4025);
DOT 1 (-225 4175);
DOT 1 (-225 4125);
DOT 1 (-225 4225);
DOT 1 (-225 4325);
DOT 1 (-225 4275);
DOT 1 (-225 4425);
DOT 1 (-225 4475);
DOT 1 (-225 4375);
DOT 1 (-225 4575);
DOT 1 (-225 4525);
DOT 1 (-225 4625);
DOT 1 (-225 4675);
DOT 1 (-225 4725);
DOT 1 (-225 4825);
DOT 1 (-225 4775);
DOT 1 (-225 4875);
DOT 1 (-225 4975);
DOT 1 (-225 4925);
DOT 1 (-225 5075);
DOT 1 (-225 5025);
DOT 1 (-225 5125);
DOT 1 (-225 5175);
DOT 1 (-2025 4975);
DOT 1 (-2025 4925);
QUIT
